G04 ================== begin FILE IDENTIFICATION RECORD ==================*
G04 Layout Name:  12004-1.brd*
G04 Film Name:    L2GND*
G04 File Format:  Gerber RS274X*
G04 File Origin:  Cadence Allegro 16.2-S033*
G04 Origin Date:  Tue Oct 16 14:36:02 2012*
G04 *
G04 Layer:  VIA CLASS/L2GND*
G04 Layer:  PIN/L2GND*
G04 Layer:  ETCH/L2GND*
G04 Layer:  DRAWING FORMAT/LAYER_PCB_STORY*
G04 Layer:  DRAWING FORMAT/LAYER_L2GND*
G04 *
G04 Offset:    (0.00 0.00)*
G04 Mirror:    No*
G04 Mode:      Negative*
G04 Rotation:  0*
G04 FullContactRelief:  No*
G04 UndefLineWidth:     6.00*
G04 ================== end FILE IDENTIFICATION RECORD ====================*
%FSLAX35Y35*MOIN*%
%IR0*IPPOS*OFA0.00000B0.00000*MIA0B0*SFA1.00000B1.00000*%
%ADD15C,.03*%
%ADD14C,.032*%
%ADD22C,.09*%
%ADD19C,.036*%
%ADD17C,.063*%
%ADD26C,.073*%
%ADD24C,.089*%
%AMMACRO16*
4,1,13,.02327,.00913,
.024502,.004951,
.024989,.000621,
.024717,-.003728,
.023695,-.007964,
.02327,-.00913,
.02707,-.01293,
.028904,-.008033,
.02986,-.002892,
.029908,.002337,
.029048,.007495,
.027305,.012426,
.02707,.01293,
.02327,.00913,
270.*
4,1,13,.00913,-.02327,
.004951,-.024502,
.000621,-.024989,
-.003728,-.024717,
-.007964,-.023695,
-.00913,-.02327,
-.01293,-.02707,
-.008033,-.028904,
-.002892,-.02986,
.002337,-.029908,
.007495,-.029048,
.012426,-.027305,
.01293,-.02707,
.00913,-.02327,
270.*
4,1,13,-.02327,-.00913,
-.024502,-.004951,
-.024989,-.000621,
-.024717,.003728,
-.023695,.007964,
-.02327,.00913,
-.02707,.01293,
-.028904,.008033,
-.02986,.002892,
-.029908,-.002337,
-.029048,-.007495,
-.027305,-.012426,
-.02707,-.01293,
-.02327,-.00913,
270.*
4,1,13,-.00913,.02327,
-.004951,.024502,
-.000621,.024989,
.003728,.024717,
.007964,.023695,
.00913,.02327,
.01293,.02707,
.008033,.028904,
.002892,.02986,
-.002337,.029908,
-.007495,.029048,
-.012426,.027305,
-.01293,.02707,
-.00913,.02327,
270.*
%
%ADD16MACRO16*%
%AMMACRO27*
4,1,15,.00398,.00044,
.003999,.000208,
.004004,-.000025,
.003996,-.000258,
.00398,-.00044,
.00483,-.00129,
.004897,-.001007,
.004947,-.000721,
.004981,-.000432,
.004997,-.000141,
.004997,.000149,
.00498,.00044,
.004946,.000729,
.004895,.001015,
.00483,.00129,
.00398,.00044,
90.*
4,1,15,.00044,-.00398,
.000208,-.003999,
-.000025,-.004004,
-.000258,-.003996,
-.00044,-.00398,
-.00129,-.00483,
-.001007,-.004897,
-.000721,-.004947,
-.000432,-.004981,
-.000141,-.004997,
.000149,-.004997,
.00044,-.00498,
.000729,-.004946,
.001015,-.004895,
.00129,-.00483,
.00044,-.00398,
90.*
4,1,15,-.00398,-.00044,
-.003999,-.000208,
-.004004,.000025,
-.003996,.000258,
-.00398,.00044,
-.00483,.00129,
-.004897,.001007,
-.004947,.000721,
-.004981,.000432,
-.004997,.000141,
-.004997,-.000149,
-.00498,-.00044,
-.004946,-.000729,
-.004895,-.001015,
-.00483,-.00129,
-.00398,-.00044,
90.*
4,1,15,-.00044,.00398,
-.000208,.003999,
.000025,.004004,
.000258,.003996,
.00044,.00398,
.00129,.00483,
.001007,.004897,
.000721,.004947,
.000432,.004981,
.000141,.004997,
-.000149,.004997,
-.00044,.00498,
-.000729,.004946,
-.001015,.004895,
-.00129,.00483,
-.00044,.00398,
90.*
%
%ADD27MACRO27*%
%AMMACRO11*
4,1,15,.00398,.00044,
.003999,.000208,
.004004,-.000025,
.003996,-.000258,
.00398,-.00044,
.00483,-.00129,
.004897,-.001007,
.004947,-.000721,
.004981,-.000432,
.004997,-.000141,
.004997,.000149,
.00498,.00044,
.004946,.000729,
.004895,.001015,
.00483,.00129,
.00398,.00044,
0.0*
4,1,15,.00044,-.00398,
.000208,-.003999,
-.000025,-.004004,
-.000258,-.003996,
-.00044,-.00398,
-.00129,-.00483,
-.001007,-.004897,
-.000721,-.004947,
-.000432,-.004981,
-.000141,-.004997,
.000149,-.004997,
.00044,-.00498,
.000729,-.004946,
.001015,-.004895,
.00129,-.00483,
.00044,-.00398,
0.0*
4,1,15,-.00398,-.00044,
-.003999,-.000208,
-.004004,.000025,
-.003996,.000258,
-.00398,.00044,
-.00483,.00129,
-.004897,.001007,
-.004947,.000721,
-.004981,.000432,
-.004997,.000141,
-.004997,-.000149,
-.00498,-.00044,
-.004946,-.000729,
-.004895,-.001015,
-.00483,-.00129,
-.00398,-.00044,
0.0*
4,1,15,-.00044,.00398,
-.000208,.003999,
.000025,.004004,
.000258,.003996,
.00044,.00398,
.00129,.00483,
.001007,.004897,
.000721,.004947,
.000432,.004981,
.000141,.004997,
-.000149,.004997,
-.00044,.00498,
-.000729,.004946,
-.001015,.004895,
-.00129,.00483,
-.00044,.00398,
0.0*
%
%ADD11MACRO11*%
%AMMACRO18*
4,1,17,.09314,.06486,
.102988,.047701,
.109706,.029093,
.113092,.0096,
.113041,-.010184,
.109555,-.029658,
.10274,-.048232,
.09314,-.06486,
.09673,-.06845,
.107147,-.050613,
.114308,-.031238,
.117996,-.010914,
.118098,.009741,
.114613,.030101,
.107644,.049546,
.097406,.067485,
.09673,.06845,
.09314,.06486,
270.*
4,1,17,.06486,-.09314,
.047701,-.102988,
.029093,-.109706,
.0096,-.113092,
-.010184,-.113041,
-.029658,-.109555,
-.048232,-.10274,
-.06486,-.09314,
-.06845,-.09673,
-.050613,-.107147,
-.031238,-.114308,
-.010914,-.117996,
.009741,-.118098,
.030101,-.114613,
.049546,-.107644,
.067485,-.097406,
.06845,-.09673,
.06486,-.09314,
270.*
4,1,17,-.09314,-.06486,
-.102988,-.047701,
-.109706,-.029093,
-.113092,-.0096,
-.113041,.010184,
-.109555,.029658,
-.10274,.048232,
-.09314,.06486,
-.09673,.06845,
-.107147,.050613,
-.114308,.031238,
-.117996,.010914,
-.118098,-.009741,
-.114613,-.030101,
-.107644,-.049546,
-.097406,-.067485,
-.09673,-.06845,
-.09314,-.06486,
270.*
4,1,17,-.06486,.09314,
-.047701,.102988,
-.029093,.109706,
-.0096,.113092,
.010184,.113041,
.029658,.109555,
.048232,.10274,
.06486,.09314,
.06845,.09673,
.050613,.107147,
.031238,.114308,
.010914,.117996,
-.009741,.118098,
-.030101,.114613,
-.049546,.107644,
-.067485,.097406,
-.06845,.09673,
-.06486,.09314,
270.*
%
%ADD18MACRO18*%
%AMMACRO21*
4,1,13,.02594,.0118,
.027595,.007116,
.028411,.002216,
.028365,-.002751,
.027456,-.007635,
.02594,-.0118,
.02968,-.01554,
.031928,-.01015,
.033205,-.004452,
.033474,.001382,
.032725,.007174,
.030982,.012747,
.02968,.01554,
.02594,.0118,
270.*
4,1,13,.0118,-.02594,
.007116,-.027595,
.002216,-.028411,
-.002751,-.028365,
-.007635,-.027456,
-.0118,-.02594,
-.01554,-.02968,
-.01015,-.031928,
-.004452,-.033205,
.001382,-.033474,
.007174,-.032725,
.012747,-.030982,
.01554,-.02968,
.0118,-.02594,
270.*
4,1,13,-.02594,-.0118,
-.027595,-.007116,
-.028411,-.002216,
-.028365,.002751,
-.027456,.007635,
-.02594,.0118,
-.02968,.01554,
-.031928,.01015,
-.033205,.004452,
-.033474,-.001382,
-.032725,-.007174,
-.030982,-.012747,
-.02968,-.01554,
-.02594,-.0118,
270.*
4,1,13,-.0118,.02594,
-.007116,.027595,
-.002216,.028411,
.002751,.028365,
.007635,.027456,
.0118,.02594,
.01554,.02968,
.01015,.031928,
.004452,.033205,
-.001382,.033474,
-.007174,.032725,
-.012747,.030982,
-.01554,.02968,
-.0118,.02594,
270.*
%
%ADD21MACRO21*%
%ADD13C,.107*%
%ADD28C,.225*%
%ADD12C,.186*%
%ADD10C,.168*%
%AMMACRO20*
4,1,13,.02442,.01028,
.025834,.005883,
.026463,.001308,
.026288,-.003307,
.025315,-.007822,
.02442,-.01028,
.02819,-.01405,
.030201,-.008941,
.031295,-.003561,
.031438,.001927,
.030626,.007357,
.028883,.012564,
.02819,.01405,
.02442,.01028,
90.*
4,1,13,.01028,-.02442,
.005883,-.025834,
.001308,-.026463,
-.003307,-.026288,
-.007822,-.025315,
-.01028,-.02442,
-.01405,-.02819,
-.008941,-.030201,
-.003561,-.031295,
.001927,-.031438,
.007357,-.030626,
.012564,-.028883,
.01405,-.02819,
.01028,-.02442,
90.*
4,1,13,-.02442,-.01028,
-.025834,-.005883,
-.026463,-.001308,
-.026288,.003307,
-.025315,.007822,
-.02442,.01028,
-.02819,.01405,
-.030201,.008941,
-.031295,.003561,
-.031438,-.001927,
-.030626,-.007357,
-.028883,-.012564,
-.02819,-.01405,
-.02442,-.01028,
90.*
4,1,13,-.01028,.02442,
-.005883,.025834,
-.001308,.026463,
.003307,.026288,
.007822,.025315,
.01028,.02442,
.01405,.02819,
.008941,.030201,
.003561,.031295,
-.001927,.031438,
-.007357,.030626,
-.012564,.028883,
-.01405,.02819,
-.01028,.02442,
90.*
%
%ADD20MACRO20*%
%AMMACRO25*
4,1,14,.02819,.01405,
.030201,.008941,
.031295,.003561,
.031438,-.001927,
.030626,-.007357,
.028883,-.012564,
.02819,-.01405,
.03189,-.01775,
.034488,-.011943,
.036038,-.005773,
.036493,.000573,
.035839,.006901,
.034096,.01302,
.03189,.01775,
.02819,.01405,
0.0*
4,1,14,.01405,-.02819,
.008941,-.030201,
.003561,-.031295,
-.001927,-.031438,
-.007357,-.030626,
-.012564,-.028883,
-.01405,-.02819,
-.01775,-.03189,
-.011943,-.034488,
-.005773,-.036038,
.000573,-.036493,
.006901,-.035839,
.01302,-.034096,
.01775,-.03189,
.01405,-.02819,
0.0*
4,1,14,-.02819,-.01405,
-.030201,-.008941,
-.031295,-.003561,
-.031438,.001927,
-.030626,.007357,
-.028883,.012564,
-.02819,.01405,
-.03189,.01775,
-.034488,.011943,
-.036038,.005773,
-.036493,-.000573,
-.035839,-.006901,
-.034096,-.01302,
-.03189,-.01775,
-.02819,-.01405,
0.0*
4,1,14,-.01405,.02819,
-.008941,.030201,
-.003561,.031295,
.001927,.031438,
.007357,.030626,
.012564,.028883,
.01405,.02819,
.01775,.03189,
.011943,.034488,
.005773,.036038,
-.000573,.036493,
-.006901,.035839,
-.01302,.034096,
-.01775,.03189,
-.01405,.02819,
0.0*
%
%ADD25MACRO25*%
%AMMACRO23*
4,1,14,.0575,.02922,
.0617,.018791,
.064026,.007792,
.064406,-.003445,
.06283,-.014576,
.059344,-.025265,
.0575,-.02922,
.06121,-.03292,
.065997,-.021791,
.068778,-.01,
.069469,.002095,
.06805,.014127,
.064563,.025729,
.06121,.03292,
.0575,.02922,
0.0*
4,1,14,.02922,-.0575,
.018791,-.0617,
.007792,-.064026,
-.003445,-.064406,
-.014576,-.06283,
-.025265,-.059344,
-.02922,-.0575,
-.03292,-.06121,
-.021791,-.065997,
-.01,-.068778,
.002095,-.069469,
.014127,-.06805,
.025729,-.064563,
.03292,-.06121,
.02922,-.0575,
0.0*
4,1,14,-.0575,-.02922,
-.0617,-.018791,
-.064026,-.007792,
-.064406,.003445,
-.06283,.014576,
-.059344,.025265,
-.0575,.02922,
-.06121,.03292,
-.065997,.021791,
-.068778,.01,
-.069469,-.002095,
-.06805,-.014127,
-.064563,-.025729,
-.06121,-.03292,
-.0575,-.02922,
0.0*
4,1,14,-.02922,.0575,
-.018791,.0617,
-.007792,.064026,
.003445,.064406,
.014576,.06283,
.025265,.059344,
.02922,.0575,
.03292,.06121,
.021791,.065997,
.01,.068778,
-.002095,.069469,
-.014127,.06805,
-.025729,.064563,
-.03292,.06121,
-.02922,.0575,
0.0*
%
%ADD23MACRO23*%
%ADD29C,.02*%
%ADD30C,.006*%
%ADD36R,.11123X.06863*%
%ADD35R,.06863X.11123*%
%ADD34C,.08506*%
%ADD33C,.08606*%
%ADD32C,.10306*%
%ADD37R,.02415X.02361*%
%ADD38R,.02415X.02317*%
%ADD31C,.18206*%
%ADD65R,.05902X.02451*%
%ADD53R,.02611X.02593*%
%ADD58R,.05742X.02451*%
%ADD45R,.02576X.0245*%
%ADD63R,.02468X.02415*%
%ADD59R,.0245X.02379*%
%ADD56R,.02486X.02361*%
%ADD42R,.0254X.02379*%
%ADD41R,.02432X.02379*%
%ADD64R,.02325X.02397*%
%ADD60R,.02397X.02361*%
%ADD50R,.02397X.02343*%
%ADD61R,.05885X.02611*%
%ADD57R,.05921X.02665*%
%ADD48R,.05831X.02665*%
%ADD54R,.05975X.0254*%
%ADD51R,.05867X.02522*%
%ADD43R,.05867X.0263*%
%ADD40R,.05903X.02468*%
%ADD39R,.05867X.02612*%
%ADD52R,.05849X.02415*%
%ADD66R,.05939X.0229*%
%ADD46R,.02557X.02379*%
%ADD49R,.02487X.02397*%
%ADD44R,.05974X.02558*%
%ADD62R,.05849X.02558*%
%ADD55R,.05849X.02486*%
%ADD47R,.05957X.02684*%
G75*
%LPD*%
G75*
G36*
G01X-149740Y-6000D02*
X795764D01*
Y931197D01*
X-149740D01*
Y-6000D01*
G37*
%LPC*%
G75*
G36*
G01X3000Y209904D02*
X2866Y210037D01*
X2854Y210095D01*
G03X-2503Y215452I-6791J-1434D01*
G01X-2561Y215464D01*
X-2694Y215598D01*
X-3704D01*
G03X-3937Y215602I-236J-6937D01*
G01X-139803D01*
G02X-140736Y216535I0J933D01*
G01Y338583D01*
G02X-139803Y339516I933J0D01*
G01X-62992D01*
G03X-62759Y339520I-3J6941D01*
G01X-61749D01*
X-61616Y339654D01*
X-61558Y339666D01*
G03X-56201Y345023I-1434J6791D01*
G01X-56189Y345081D01*
X-56055Y345214D01*
Y346224D01*
G03X-56051Y346457I-6937J236D01*
G01Y503937D01*
G02X-55118Y504870I933J0D01*
G01X-3937D01*
G03X-3704Y504874I-3J6941D01*
G01X-2694D01*
X-2560Y505008D01*
X-2502Y505020D01*
G03X2854Y510376I-1435J6791D01*
G01X2866Y510434D01*
X3000Y510568D01*
Y511578D01*
G03X3004Y511811I-6937J236D01*
G01Y783465D01*
G02X3937Y784398I933J0D01*
G01X74803D01*
G03X75036Y784402I-3J6941D01*
G01X76046D01*
X76179Y784536D01*
X76237Y784548D01*
G03X81594Y789905I-1434J6791D01*
G01X81606Y789963D01*
X81740Y790096D01*
Y791106D01*
G03X81744Y791339I-6937J236D01*
G01Y921260D01*
G02X82677Y922193I933J0D01*
G01X755906D01*
G02X756839Y921260I0J-933D01*
G01Y821457D01*
G03X763780Y814516I6941J0D01*
G01X767612D01*
X767616Y814520D01*
X773015D01*
Y792173D01*
X771286D01*
X771282Y792177D01*
X765945D01*
G03Y778689I0J-6744D01*
G01X772462D01*
X772466Y778693D01*
X773015D01*
Y740602D01*
X763780D01*
G03X756839Y733661I0J-6941D01*
G01Y663976D01*
G03X763780Y657035I6941J0D01*
G01X765572D01*
X765576Y657039D01*
X773015D01*
Y382724D01*
X770786D01*
X770782Y382728D01*
X765945D01*
G03Y369240I0J-6744D01*
G01X770062D01*
X770066Y369244D01*
X773015D01*
Y331150D01*
X767436D01*
X767432Y331154D01*
X763780D01*
G03X763547Y331150I3J-6941D01*
G01X762537D01*
X762404Y331016D01*
X762346Y331004D01*
G03X756989Y325647I1434J-6791D01*
G01X756977Y325589D01*
X756843Y325456D01*
Y324446D01*
G03X756839Y324213I6937J-236D01*
G01Y3937D01*
G02X755906Y3004I-933J0D01*
G01X3937D01*
G02X3004Y3937I0J933D01*
G01Y208661D01*
G03X3000Y208894I-6941J-3D01*
G01Y209904D01*
G37*
%LPD*%
G75*
G36*
G01X708866Y31408D02*
X708859Y31414D01*
X708852Y31421D01*
G02X708179Y32132I7684J7948D01*
G01X708148Y32166D01*
X708120Y32201D01*
G02X706495Y34742I8414J7171D01*
G01X706486Y34761D01*
X706480Y34776D01*
G02X705946Y36193I10054J4598D01*
G01X705945Y36197D01*
X705944Y36202D01*
G02X705542Y38197I10590J3172D01*
G01X705541Y38207D01*
X705540Y38220D01*
G02X706596Y44211I10995J1151D01*
G01X706602Y44223D01*
G02X708278Y46721I9933J-4853D01*
G01X708318Y46768D01*
X708364Y46816D01*
G02X710669Y48740I8171J-7446D01*
G01X710671Y48742D01*
G02X712010Y49457I5865J-9372D01*
G01X712040Y49471D01*
X712070Y49483D01*
G02X712988Y49841I4472J-10110D01*
G01X712996Y49843D01*
G02X720074I3539J-10473D01*
G01X720082Y49841D01*
G02X721000Y49483I-3554J-10468D01*
G01X721030Y49471D01*
X721060Y49457D01*
G02X722399Y48742I-4526J-10087D01*
G01X722401Y48740D01*
G02X724706Y46816I-5866J-9370D01*
G01X724752Y46768D01*
X724792Y46721D01*
G02X726468Y44223I-8257J-7351D01*
G01X726474Y44211D01*
G02X727530Y38220I-9939J-4840D01*
G01X727529Y38207D01*
X727528Y38197D01*
G02X727126Y36202I-10992J1177D01*
G01X727125Y36197D01*
X727124Y36193D01*
G02X726590Y34776I-10588J3181D01*
G01X726584Y34761D01*
X726575Y34742D01*
G02X724950Y32201I-10039J4630D01*
G01X724922Y32166D01*
X724891Y32132D01*
G02X724218Y31421I-8357J7237D01*
G01X724211Y31414D01*
X724204Y31408D01*
G02X708866I-7669J7962D01*
G37*
G36*
G01X177945Y852442D02*
X172311D01*
X172309Y852444D01*
X172232Y852448D01*
G02X172360Y853851I34J704D01*
G01X172373Y853849D01*
X178012D01*
X178068Y853841D01*
G02X177945Y852442I-95J-697D01*
G37*
G36*
G01X168065Y850867D02*
X162431D01*
X162429Y850869D01*
X162352Y850873D01*
G02X162480Y852276I34J704D01*
G01X162493Y852274D01*
X168131D01*
X168188Y852266D01*
G02X168065Y850867I-97J-696D01*
G37*
G36*
G01X177945Y849292D02*
X172311D01*
X172309Y849294D01*
X172232Y849298D01*
G02X172360Y850701I34J704D01*
G01X172373Y850699D01*
X178012D01*
X178068Y850691D01*
G02X177945Y849292I-95J-697D01*
G37*
G36*
G01X168065Y847717D02*
X162431D01*
X162429Y847719D01*
X162352Y847723D01*
G02X162480Y849126I34J704D01*
G01X162493Y849124D01*
X168131D01*
X168188Y849116D01*
G02X168065Y847717I-97J-696D01*
G37*
G36*
G01X177945Y842992D02*
X172311D01*
X172309Y842994D01*
X172232Y842998D01*
G02X172360Y844401I34J704D01*
G01X172373Y844399D01*
X178012D01*
X178068Y844391D01*
G02X177945Y842992I-95J-697D01*
G37*
G36*
G01X168065Y841417D02*
X162431D01*
X162429Y841419D01*
X162352Y841423D01*
G02X162480Y842826I34J704D01*
G01X162493Y842824D01*
X168131D01*
X168188Y842816D01*
G02X168065Y841417I-97J-696D01*
G37*
G36*
G01X177945Y839842D02*
X172311D01*
X172309Y839844D01*
X172232Y839848D01*
G02X172360Y841251I34J704D01*
G01X172373Y841249D01*
X178012D01*
X178068Y841241D01*
G02X177945Y839842I-95J-697D01*
G37*
G36*
G01X168065Y838267D02*
X162431D01*
X162429Y838269D01*
X162352Y838273D01*
G02X162480Y839676I34J704D01*
G01X162493Y839674D01*
X168131D01*
X168188Y839666D01*
G02X168065Y838267I-97J-696D01*
G37*
G36*
G01X177945Y833547D02*
X172311D01*
X172309Y833549D01*
X172232Y833553D01*
G02X172360Y834956I34J704D01*
G01X172373Y834954D01*
X178011D01*
X178068Y834946D01*
G02X177945Y833547I-97J-696D01*
G37*
G36*
G01X168065Y831972D02*
X162431D01*
X162429Y831974D01*
X162352Y831978D01*
G02X162480Y833381I34J704D01*
G01X162493Y833379D01*
X168131D01*
X168188Y833371D01*
G02X168065Y831972I-97J-696D01*
G37*
G36*
G01X177945Y830397D02*
X172311D01*
X172309Y830399D01*
X172232Y830403D01*
G02X172360Y831806I34J704D01*
G01X172373Y831804D01*
X178011D01*
X178068Y831796D01*
G02X177945Y830397I-97J-696D01*
G37*
G36*
G01X168065Y828822D02*
X162431D01*
X162429Y828824D01*
X162352Y828828D01*
G02X162480Y830231I34J704D01*
G01X162493Y830229D01*
X168131D01*
X168188Y830221D01*
G02X168065Y828822I-97J-696D01*
G37*
G36*
G01X177945Y824097D02*
X172311D01*
X172309Y824099D01*
X172232Y824103D01*
G02X172360Y825506I34J704D01*
G01X172373Y825504D01*
X178011D01*
X178068Y825496D01*
G02X177945Y824097I-97J-696D01*
G37*
G36*
G01X168065Y822522D02*
X162431D01*
X162429Y822524D01*
X162352Y822528D01*
G02X162480Y823931I34J704D01*
G01X162493Y823929D01*
X168131D01*
X168188Y823921D01*
G02X168065Y822522I-97J-696D01*
G37*
G36*
G01X177945Y820947D02*
X172311D01*
X172309Y820949D01*
X172232Y820953D01*
G02X172360Y822356I34J704D01*
G01X172373Y822354D01*
X178011D01*
X178068Y822346D01*
G02X177945Y820947I-97J-696D01*
G37*
G36*
G01X168065Y819372D02*
X162431D01*
X162429Y819374D01*
X162352Y819378D01*
G02X162480Y820781I34J704D01*
G01X162493Y820779D01*
X168131D01*
X168188Y820771D01*
G02X168065Y819372I-97J-696D01*
G37*
G36*
G01X87828Y730394D02*
X82194D01*
X82192Y730396D01*
X82115Y730400D01*
G02X82243Y731803I34J704D01*
G01X82256Y731801D01*
X87895D01*
X87951Y731793D01*
G02X87828Y730394I-95J-697D01*
G37*
G36*
G01X77946Y728820D02*
X72312D01*
X72310Y728822D01*
X72233Y728826D01*
G02X72361Y730229I34J704D01*
G01X72374Y730227D01*
X78012D01*
X78069Y730219D01*
G02X77946Y728820I-97J-696D01*
G37*
G36*
G01X87828Y727245D02*
X82194D01*
X82192Y727247D01*
X82115Y727251D01*
G02X82243Y728654I34J704D01*
G01X82256Y728652D01*
X87894D01*
X87951Y728644D01*
G02X87828Y727245I-97J-696D01*
G37*
G36*
G01X77946Y725670D02*
X72312D01*
X72310Y725672D01*
X72233Y725676D01*
G02X72361Y727079I34J704D01*
G01X72374Y727077D01*
X78013D01*
X78069Y727069D01*
G02X77946Y725670I-95J-697D01*
G37*
G36*
G01X87828Y720946D02*
X82194D01*
X82192Y720948D01*
X82115Y720952D01*
G02X82243Y722355I34J704D01*
G01X82256Y722353D01*
X87894D01*
X87951Y722345D01*
G02X87828Y720946I-97J-696D01*
G37*
G36*
G01X77946Y719371D02*
X72312D01*
X72310Y719373D01*
X72233Y719377D01*
G02X72361Y720780I34J704D01*
G01X72374Y720778D01*
X78012D01*
X78069Y720770D01*
G02X77946Y719371I-97J-696D01*
G37*
G36*
G01X87828Y717796D02*
X82194D01*
X82192Y717798D01*
X82115Y717802D01*
G02X82243Y719205I34J704D01*
G01X82256Y719203D01*
X87894D01*
X87951Y719195D01*
G02X87828Y717796I-97J-696D01*
G37*
G36*
G01X77946Y716221D02*
X72312D01*
X72310Y716223D01*
X72233Y716227D01*
G02X72361Y717630I34J704D01*
G01X72374Y717628D01*
X78012D01*
X78069Y717620D01*
G02X77946Y716221I-97J-696D01*
G37*
G36*
G01X87828Y695749D02*
X82194D01*
X82192Y695751D01*
X82115Y695755D01*
G02X82243Y697158I34J704D01*
G01X82256Y697156D01*
X87894D01*
X87951Y697148D01*
G02X87828Y695749I-97J-696D01*
G37*
G36*
G01X77946Y694174D02*
X72312D01*
X72310Y694176D01*
X72233Y694180D01*
G02X72361Y695583I34J704D01*
G01X72374Y695581D01*
X78012D01*
X78069Y695573D01*
G02X77946Y694174I-97J-696D01*
G37*
G36*
G01X87828Y692599D02*
X82194D01*
X82192Y692601D01*
X82115Y692605D01*
G02X82243Y694008I34J704D01*
G01X82256Y694006D01*
X87894D01*
X87951Y693998D01*
G02X87828Y692599I-97J-696D01*
G37*
G36*
G01X77946Y691024D02*
X72312D01*
X72310Y691026D01*
X72233Y691030D01*
G02X72361Y692433I34J704D01*
G01X72374Y692431D01*
X78012D01*
X78069Y692423D01*
G02X77946Y691024I-97J-696D01*
G37*
G36*
G01X87828Y686300D02*
X82194D01*
X82192Y686302D01*
X82115Y686306D01*
G02X82243Y687709I34J704D01*
G01X82256Y687707D01*
X87894D01*
X87951Y687699D01*
G02X87828Y686300I-97J-696D01*
G37*
G36*
G01X77946Y684725D02*
X72312D01*
X72310Y684727D01*
X72233Y684731D01*
G02X72361Y686134I34J704D01*
G01X72374Y686132D01*
X78013D01*
X78069Y686124D01*
G02X77946Y684725I-95J-697D01*
G37*
G36*
G01X87828Y683150D02*
X82194D01*
X82192Y683152D01*
X82115Y683156D01*
G02X82243Y684559I34J704D01*
G01X82256Y684557D01*
X87894D01*
X87951Y684549D01*
G02X87828Y683150I-97J-696D01*
G37*
G36*
G01X77946Y681576D02*
X72312D01*
X72310Y681578D01*
X72233Y681582D01*
G02X72361Y682985I34J704D01*
G01X72374Y682983D01*
X78012D01*
X78069Y682975D01*
G02X77946Y681576I-97J-696D01*
G37*
G36*
G01X87832Y612285D02*
X82198D01*
X82196Y612287D01*
X82119Y612291D01*
G02X82247Y613694I34J704D01*
G01X82260Y613692D01*
X87898D01*
X87955Y613684D01*
G02X87832Y612285I-97J-696D01*
G37*
G36*
G01X77946Y610710D02*
X72312D01*
X72310Y610712D01*
X72233Y610716D01*
G02X72361Y612119I34J704D01*
G01X72374Y612117D01*
X78012D01*
X78069Y612109D01*
G02X77946Y610710I-97J-696D01*
G37*
G36*
G01X87828Y609135D02*
X82194D01*
X82192Y609137D01*
X82115Y609141D01*
G02X82243Y610544I34J704D01*
G01X82256Y610542D01*
X87894D01*
X87951Y610534D01*
G02X87828Y609135I-97J-696D01*
G37*
G36*
G01X77946Y607560D02*
X72312D01*
X72310Y607562D01*
X72233Y607566D01*
G02X72361Y608969I34J704D01*
G01X72374Y608967D01*
X78012D01*
X78069Y608959D01*
G02X77946Y607560I-97J-696D01*
G37*
G36*
G01X87828Y602836D02*
X82194D01*
X82192Y602838D01*
X82115Y602842D01*
G02X82243Y604245I34J704D01*
G01X82256Y604243D01*
X87894D01*
X87951Y604235D01*
G02X87828Y602836I-97J-696D01*
G37*
G36*
G01X77946Y601261D02*
X72312D01*
X72310Y601263D01*
X72233Y601267D01*
G02X72361Y602670I34J704D01*
G01X72374Y602668D01*
X78012D01*
X78069Y602660D01*
G02X77946Y601261I-97J-696D01*
G37*
G36*
G01X87828Y599686D02*
X82194D01*
X82192Y599688D01*
X82115Y599692D01*
G02X82243Y601095I34J704D01*
G01X82256Y601093D01*
X87894D01*
X87951Y601085D01*
G02X87828Y599686I-97J-696D01*
G37*
G36*
G01X77946Y598111D02*
X72312D01*
X72310Y598113D01*
X72233Y598117D01*
G02X72361Y599520I34J704D01*
G01X72374Y599518D01*
X78012D01*
X78069Y599510D01*
G02X77946Y598111I-97J-696D01*
G37*
G36*
G01X87828Y577639D02*
X82194D01*
X82192Y577641D01*
X82115Y577645D01*
G02X82243Y579048I34J704D01*
G01X82256Y579046D01*
X87894D01*
X87951Y579038D01*
G02X87828Y577639I-97J-696D01*
G37*
G36*
G01X77946Y576064D02*
X72312D01*
X72310Y576066D01*
X72233Y576070D01*
G02X72361Y577473I34J704D01*
G01X72374Y577471D01*
X78013D01*
X78069Y577463D01*
G02X77946Y576064I-95J-697D01*
G37*
G36*
G01X87828Y574489D02*
X82194D01*
X82192Y574491D01*
X82115Y574495D01*
G02X82243Y575898I34J704D01*
G01X82256Y575896D01*
X87894D01*
X87951Y575888D01*
G02X87828Y574489I-97J-696D01*
G37*
G36*
G01X77946Y572914D02*
X72312D01*
X72310Y572916D01*
X72233Y572920D01*
G02X72361Y574323I34J704D01*
G01X72374Y574321D01*
X78013D01*
X78069Y574313D01*
G02X77946Y572914I-95J-697D01*
G37*
G36*
G01X87828Y568190D02*
X82194D01*
X82192Y568192D01*
X82115Y568196D01*
G02X82243Y569599I34J704D01*
G01X82256Y569597D01*
X87895D01*
X87951Y569589D01*
G02X87828Y568190I-95J-697D01*
G37*
G36*
G01X77946Y566615D02*
X72312D01*
X72310Y566617D01*
X72233Y566621D01*
G02X72361Y568024I34J704D01*
G01X72374Y568022D01*
X78012D01*
X78069Y568014D01*
G02X77946Y566615I-97J-696D01*
G37*
G36*
G01X87828Y565040D02*
X82194D01*
X82192Y565042D01*
X82115Y565046D01*
G02X82243Y566449I34J704D01*
G01X82256Y566447D01*
X87895D01*
X87951Y566439D01*
G02X87828Y565040I-95J-697D01*
G37*
G36*
G01X77946Y563466D02*
X72312D01*
X72310Y563468D01*
X72233Y563472D01*
G02X72361Y564875I34J704D01*
G01X72374Y564873D01*
X78013D01*
X78069Y564865D01*
G02X77946Y563466I-95J-697D01*
G37*
G54D36*
X245709Y362136D03*
X241718Y373088D03*
G54D35*
X145822Y327672D03*
X123260Y327770D03*
X156726Y331834D03*
X134528Y332005D03*
X167582Y336068D03*
X178608Y339793D03*
X189754Y344270D03*
X200804Y348410D03*
X211878Y352304D03*
X222978Y359872D03*
X45936Y521235D03*
X68180Y521364D03*
X90426Y521510D03*
X112468Y521766D03*
X201292Y521826D03*
X179046Y521851D03*
X156994Y521898D03*
X134966Y521923D03*
X57252Y525428D03*
X101476Y525646D03*
X79376Y525720D03*
X123795Y525916D03*
X212414Y525989D03*
X145846Y526012D03*
X168118D03*
X190194Y526085D03*
G54D34*
X144843Y812994D03*
Y860234D03*
G54D33*
X54724Y557087D03*
Y620079D03*
Y675197D03*
Y738189D03*
X144843Y798779D03*
Y874449D03*
G54D32*
X-33503Y269685D03*
G54D37*
X678468Y450352D03*
X661692Y466893D03*
X732096Y471132D03*
G54D38*
X711372Y450508D03*
G54D31*
X-59094Y277559D03*
X-7913D03*
G54D65*
X651112Y482696D03*
G54D53*
X727812Y466866D03*
G54D58*
X730415Y474556D03*
G54D45*
X719656Y458637D03*
G54D63*
X649395Y479369D03*
G54D59*
X653536Y475057D03*
G54D56*
X657525Y471006D03*
G54D42*
X715506Y454560D03*
G54D41*
X674151Y454558D03*
G54D64*
X740334Y479448D03*
G54D60*
X736148Y475210D03*
G54D50*
X665888Y462734D03*
G54D61*
X655182Y478448D03*
G54D57*
X659278Y474324D03*
G54D48*
X717974Y462072D03*
G54D54*
X663490Y470202D03*
G54D51*
X667604Y466114D03*
G54D43*
X675796Y457886D03*
G54D40*
X709658Y453932D03*
G54D39*
X680230Y453715D03*
G54D52*
X722080Y466132D03*
G54D66*
X738580Y482829D03*
G54D46*
X670028Y458656D03*
G54D49*
X723762Y462706D03*
G54D44*
X713789Y457994D03*
G54D62*
X734476Y478581D03*
G54D55*
X726158Y470246D03*
G54D47*
X671780Y461991D03*
G54D15*
X8789Y376072D03*
X6944Y414616D03*
X6855Y436844D03*
X6750Y425868D03*
X7180Y449205D03*
X62439Y413744D03*
X66931Y398350D03*
X74863Y390483D03*
X64055Y389700D03*
X33722Y401639D03*
X74544Y414071D03*
X70779Y402387D03*
X79016Y410283D03*
X35738Y406956D03*
X14422Y411528D03*
X14657Y416838D03*
X10615Y411073D03*
X26551Y394546D03*
X30232Y416556D03*
X23922Y415548D03*
X35994Y410146D03*
X43719Y414419D03*
X32141Y407501D03*
X31808Y410684D03*
X18448Y402542D03*
X74817Y409752D03*
X26972Y399588D03*
X70882Y409794D03*
X66938Y410045D03*
X78939Y414083D03*
X18448Y406788D03*
X53976Y389814D03*
X74894Y398251D03*
X62031Y399713D03*
X74702Y394300D03*
X74869Y406315D03*
X78300Y386505D03*
X64948Y386626D03*
X78362Y398337D03*
X77963Y381183D03*
X70888Y394222D03*
X66963Y473083D03*
X66931Y484968D03*
X79081Y465348D03*
X70704Y429620D03*
X67015Y449433D03*
X74639Y441855D03*
X78754Y453353D03*
X78811Y426113D03*
X52151Y456887D03*
X66903Y457689D03*
X78798Y433983D03*
X17072Y435057D03*
X74836Y453477D03*
X59980Y482517D03*
X78754Y449904D03*
X67112Y481066D03*
X70488Y465291D03*
X74450Y457429D03*
X70713Y461504D03*
X36237Y441728D03*
X70908Y457771D03*
X70898Y418271D03*
X61038Y424878D03*
X74726Y425594D03*
X59209Y438908D03*
X46853Y441796D03*
X78561Y421756D03*
X70809Y438057D03*
X43659Y432766D03*
X43088Y438073D03*
X45486Y456341D03*
X38566Y451290D03*
X42312Y463368D03*
X74780Y429794D03*
X24357Y423051D03*
X37988Y438328D03*
X19757Y418538D03*
X29472Y428016D03*
X78738Y429679D03*
X11964Y421332D03*
X52476Y439395D03*
X13062Y429279D03*
X74656Y421838D03*
X17936Y431103D03*
X14206Y433632D03*
X15424Y422722D03*
X70857Y433857D03*
X19015Y426461D03*
X14147Y438989D03*
X74752Y437655D03*
X74437Y473159D03*
X15872Y441916D03*
X74460Y461287D03*
X78793Y445704D03*
X70868Y477094D03*
X23748Y436249D03*
X26611Y441743D03*
X70909Y469595D03*
X30513Y437850D03*
X74702Y469183D03*
X37420Y461517D03*
X31517Y445328D03*
X70868Y473157D03*
X28472Y447107D03*
X48298Y454813D03*
X70602Y453533D03*
X74805Y477094D03*
X70868Y481031D03*
X74598Y485021D03*
X78421Y473078D03*
X74695Y449260D03*
X59063Y485583D03*
X79134Y461339D03*
X74870Y488789D03*
X69523Y567387D03*
X69555Y564187D03*
X69599Y601527D03*
X69569Y598159D03*
X69388Y576660D03*
X69450Y573460D03*
X69569Y608021D03*
X69496Y611417D03*
X69661Y591387D03*
X66579Y592250D03*
X63125Y592801D03*
X62681Y589462D03*
X69451Y684303D03*
Y681103D03*
Y691003D03*
X69474Y694403D03*
X69523Y718313D03*
Y715113D03*
X69472Y729385D03*
X69548Y726185D03*
X145771Y414191D03*
X82555Y406288D03*
X110472Y394496D03*
X145765Y406438D03*
X122053Y406224D03*
X114175Y410161D03*
X125990Y394413D03*
X141738D03*
X98427Y414098D03*
X125990D03*
X90553Y410161D03*
X102263Y414083D03*
X141887Y410202D03*
X102364Y406224D03*
X133864Y410161D03*
X94367Y394479D03*
X102364Y402287D03*
X106301Y398350D03*
Y402287D03*
X102364Y398350D03*
X110238Y402287D03*
X114175D03*
X110238Y398350D03*
X114175D03*
X85721Y385798D03*
X149362Y413951D03*
X149498Y406396D03*
X114175Y406224D03*
X126063Y406183D03*
X141738Y406224D03*
X106301D03*
X149663Y410083D03*
X82459Y413976D03*
X90566Y394383D03*
X82663Y402406D03*
X133864Y402287D03*
X86772Y414047D03*
X122053Y402287D03*
X133864Y398350D03*
X137801D03*
X122053D03*
X137801Y402287D03*
X125990D03*
Y398350D03*
X129927Y402287D03*
Y398350D03*
X82663Y398383D03*
X141738Y402287D03*
Y398350D03*
X145865Y402287D03*
Y398350D03*
X149488Y402114D03*
X149583Y398383D03*
X90359Y469275D03*
X137801Y453472D03*
Y445598D03*
X133864Y437720D03*
Y445598D03*
X133953Y425813D03*
X102684Y445671D03*
X106263Y437583D03*
X133864Y433783D03*
X102364Y429846D03*
X98363Y421883D03*
X94263Y418129D03*
X106210Y421976D03*
X110332Y425814D03*
X149612Y445598D03*
Y433783D03*
X86493Y441401D03*
X86616Y433783D03*
X86687Y421669D03*
X137801Y477094D03*
X149612D03*
X114175D03*
X102364D03*
X98626Y477049D03*
X130081Y425912D03*
X121943Y425834D03*
X114091Y425962D03*
X122053Y421972D03*
Y418035D03*
X106301D03*
X114175D03*
X133863Y417883D03*
X117951Y437592D03*
X114175Y445598D03*
X110263Y441683D03*
X118189Y445711D03*
X125990Y445598D03*
X110238Y437720D03*
X125990D03*
X110222Y417989D03*
X106341Y426062D03*
X82564Y449659D03*
X145663Y441483D03*
X98288Y441609D03*
X149612Y429846D03*
X110238Y453472D03*
X122053Y429846D03*
X114063Y429879D03*
X125897Y453240D03*
X118238Y453417D03*
X149594Y480923D03*
X94518Y449186D03*
X86768Y449383D03*
X98427Y484968D03*
Y481031D03*
X102364D03*
Y484968D03*
X106301D03*
Y481031D03*
X114175Y484968D03*
Y481031D03*
X122053Y484968D03*
Y481031D03*
X125990Y484968D03*
Y481031D03*
X145567Y453547D03*
X145763Y449583D03*
X149576Y465497D03*
X98597Y457291D03*
X94490Y429846D03*
X90463Y425983D03*
X90480Y437608D03*
X82562Y425980D03*
X86505Y425987D03*
X90380Y429650D03*
X130080Y457372D03*
X94490Y437720D03*
X82681Y430041D03*
X141827Y461346D03*
X98334Y429754D03*
X98427Y437720D03*
X94369Y425977D03*
X82677Y433595D03*
X149563Y469220D03*
X94490Y433783D03*
X141738Y481031D03*
X82663Y457486D03*
X141738Y484968D03*
X98433Y449125D03*
X137801Y481031D03*
X102600Y425983D03*
X137801Y484968D03*
X94554Y421911D03*
X133864Y481031D03*
X149612Y437720D03*
X94414Y445605D03*
X133864Y484968D03*
X86663Y429536D03*
X82542Y445403D03*
X98427Y433783D03*
X86568Y445669D03*
X90426Y449431D03*
X90563Y417983D03*
X145675Y425909D03*
X82573Y441360D03*
X145675Y437720D03*
X98280Y445405D03*
X90426Y441880D03*
X145675Y481031D03*
Y484968D03*
X145737Y418077D03*
X141738Y429846D03*
X86663Y453583D03*
X82732Y453139D03*
X102227Y473344D03*
X145675Y469220D03*
X90376Y476918D03*
X110238Y477094D03*
X141738D03*
X137801Y473157D03*
X98427Y469046D03*
X106301Y469220D03*
X114175D03*
X126057Y469287D03*
X129927Y469220D03*
X137801D03*
X122053Y465283D03*
X133864D03*
X106301Y461346D03*
X122113Y457535D03*
X129963Y461283D03*
X110263Y457283D03*
X122158Y453388D03*
X125990Y477094D03*
X137801Y449535D03*
X149612Y425909D03*
X82535Y461227D03*
X83021Y473118D03*
X141595Y421932D03*
X141775Y426153D03*
X86735Y461382D03*
X141763Y437883D03*
X86937Y477160D03*
X141682Y417902D03*
X82759Y469436D03*
X145663Y445583D03*
X145675Y429846D03*
X142008Y457429D03*
X141863Y445583D03*
X86959Y469276D03*
X137570Y421843D03*
X145561Y421879D03*
X90965Y465270D03*
X129927Y481031D03*
Y484968D03*
X110238Y481031D03*
Y484968D03*
X94490Y481031D03*
X86663Y457283D03*
X94490Y484968D03*
X86765Y465205D03*
X138061Y418151D03*
X145675Y433783D03*
X82763Y417750D03*
X86523Y417943D03*
X94844Y469182D03*
X102469Y469134D03*
X106149Y457371D03*
X141649Y453189D03*
X149620Y485149D03*
X98682Y461441D03*
X94092Y492819D03*
X118004Y488825D03*
X133864Y488905D03*
X149612D03*
X102308Y488978D03*
X86616Y488905D03*
X91198Y595087D03*
X91123Y591887D03*
X91223Y588487D03*
X159768Y238444D03*
X160004Y233894D03*
X181576Y407810D03*
X175463Y413760D03*
X161499Y402554D03*
X169297Y402536D03*
X157502Y390427D03*
X173425Y390228D03*
X214660Y362600D03*
X176751Y387090D03*
X157251Y414149D03*
X161477Y394511D03*
X180991Y398678D03*
X180809Y414170D03*
X179225Y403667D03*
X153587Y406496D03*
X157554Y402251D03*
X157698Y406313D03*
X161475Y410299D03*
X165266Y409882D03*
X165337Y414489D03*
X153528Y410052D03*
X165455Y398256D03*
X165229Y402019D03*
X157411Y398513D03*
X169113Y398299D03*
X178031Y390023D03*
X177588Y482616D03*
X161423Y469220D03*
X153583Y461058D03*
X169297Y477094D03*
Y465283D03*
X157486Y437720D03*
Y429846D03*
X153416Y445539D03*
X169290Y417960D03*
X169297Y437720D03*
X169112Y453260D03*
X169166Y429679D03*
X153549Y429846D03*
X165621Y418066D03*
X153549Y425909D03*
X161746Y421972D03*
X177182Y467018D03*
X175477Y472360D03*
X176815Y479061D03*
X161473Y457213D03*
X165360Y477094D03*
X153549Y437720D03*
X157560Y445484D03*
X153549Y449535D03*
X174859Y469220D03*
X157322Y453385D03*
X165317Y461561D03*
X165360Y473157D03*
X161455Y453385D03*
X177763Y486293D03*
X153463Y453383D03*
X157411Y469344D03*
X161423Y477094D03*
X157486Y461346D03*
X153690Y469111D03*
X165411Y429590D03*
X175161Y434723D03*
X161423Y445598D03*
X153549Y421972D03*
X161423Y449430D03*
X153549Y473157D03*
X161670Y418161D03*
X176662Y418122D03*
X153201Y418097D03*
X157401Y418143D03*
X157463Y421883D03*
X157486Y425909D03*
X173458Y457178D03*
X178053Y474260D03*
X174601Y481467D03*
X165319Y453134D03*
X165353Y480812D03*
X157486Y433783D03*
X165360Y421972D03*
X153646Y457393D03*
X161294Y461561D03*
X165363Y425783D03*
X157393Y457572D03*
X165217Y457361D03*
X165355Y433382D03*
X161423Y473157D03*
X165355Y437582D03*
X165360Y445598D03*
X157411Y449556D03*
X169157Y445598D03*
X157508Y480990D03*
X165288Y449306D03*
X157486Y484968D03*
X153601Y480894D03*
X153586Y485118D03*
X161423Y433783D03*
X181414Y490281D03*
X174475Y488016D03*
X178084Y493198D03*
X159589Y817543D03*
X159688Y832484D03*
X159431Y838974D03*
X159688Y829234D03*
X159137Y820712D03*
X159688Y851564D03*
X159560Y842172D03*
X159426Y848357D03*
X662166Y456914D03*
X661760Y460089D03*
X646246Y475961D03*
X646794Y472634D03*
X682915Y467823D03*
X708059Y449951D03*
X671145Y454348D03*
X658195Y464248D03*
X653351Y470098D03*
X650837Y472421D03*
X646251Y479161D03*
X675745Y448189D03*
X735191Y453967D03*
X735231Y457167D03*
X746845Y476389D03*
Y473189D03*
X717993Y451389D03*
X731751Y464398D03*
X735259Y469898D03*
X721445Y455789D03*
X726589Y460909D03*
X743520Y478297D03*
X738745Y472789D03*
X713845Y447289D03*
G54D14*
X9243Y334400D03*
X8788Y453864D03*
X63400Y89300D03*
X51900Y83600D03*
X43980Y86200D03*
X68000Y87750D03*
X42700Y110500D03*
X67300Y107200D03*
X63100Y107300D03*
X51800Y93500D03*
X79600Y91500D03*
X51900Y89900D03*
X79500Y85700D03*
X77200Y95500D03*
X69800Y176800D03*
X31500Y185700D03*
X76250Y148850D03*
X70200Y199300D03*
X29600Y200100D03*
X26100Y187300D03*
X39800Y172900D03*
X27800Y191100D03*
X74700Y191700D03*
X70675Y145000D03*
X60009Y255077D03*
X55624Y255132D03*
X59523Y271123D03*
X60102Y263180D03*
X55883Y263570D03*
X33400Y266400D03*
X59258Y246890D03*
X60069Y237965D03*
X64700Y215100D03*
X51600Y217000D03*
X50500Y243100D03*
X70636Y272953D03*
X79189Y235119D03*
X76019Y222534D03*
X42507Y296616D03*
X59316Y300366D03*
X59096Y289139D03*
X59523Y281330D03*
X52257Y276649D03*
X55420Y288656D03*
X17100Y311700D03*
X61776Y367194D03*
X43345Y386857D03*
X43639Y374043D03*
X29700Y355000D03*
X27284Y358500D03*
X67527Y381818D03*
X51422Y473540D03*
X24315Y472668D03*
X47307Y465104D03*
X29064Y471345D03*
X55295Y479672D03*
X20928Y453864D03*
X21300Y468000D03*
X38800Y535700D03*
X38200Y528900D03*
X51383Y514037D03*
X63862Y512438D03*
X73542Y514340D03*
X37200Y513500D03*
X32026Y516764D03*
X60800Y505200D03*
X67244Y535455D03*
X72677Y528615D03*
X59379Y644787D03*
X57500Y662600D03*
X47000Y645300D03*
X60122Y747800D03*
X64000Y765600D03*
X47100Y746000D03*
X65447Y711413D03*
X62066Y711051D03*
X65356Y707010D03*
X61193Y706973D03*
X106300Y105900D03*
X81150Y120850D03*
X89400Y120800D03*
X85250Y120850D03*
X117500Y106200D03*
X85000Y107800D03*
X111700Y106100D03*
X89000Y107700D03*
X132500Y124600D03*
X83800Y188800D03*
X111482Y202800D03*
X113815Y194333D03*
X122400Y199000D03*
X80685Y192398D03*
X84641Y204036D03*
X93303Y154970D03*
X144950Y177338D03*
X85713Y151540D03*
X84900Y145300D03*
X125700Y225200D03*
X121000Y225300D03*
X109400Y225400D03*
X90813D03*
X79800Y225900D03*
X87227Y242891D03*
X87263Y264658D03*
X90652Y265960D03*
X87698Y246708D03*
X94051Y265872D03*
X91230Y247047D03*
X91819Y250396D03*
X94793Y252595D03*
X98211Y252758D03*
X142933Y251431D03*
X132651Y255357D03*
X138228Y260175D03*
X124933Y270414D03*
X136427Y251413D03*
X124874Y273953D03*
X137809Y247647D03*
X135592Y257933D03*
X116566Y254205D03*
X114229Y270684D03*
X119242Y252107D03*
X112042Y275903D03*
X121685Y249741D03*
X121741Y246341D03*
X118219Y274497D03*
X122572Y258147D03*
X121599Y274869D03*
X130567Y258051D03*
X113558Y261260D03*
X111008Y242830D03*
X106381Y259865D03*
X106504Y243329D03*
X103610Y268626D03*
X102713Y242975D03*
X103003Y260260D03*
X108652Y247260D03*
X107887Y266647D03*
X101242Y265901D03*
X100415Y246679D03*
X126611Y258265D03*
X84863Y229783D03*
X134529Y264470D03*
X137190Y266587D03*
X131901Y267444D03*
X132163Y271041D03*
X137690Y273752D03*
X110610Y206436D03*
X109534Y314564D03*
X92682Y331571D03*
X140103Y328216D03*
X117460Y335158D03*
X128964Y339470D03*
X148102Y338366D03*
X119603Y285731D03*
X124478Y280855D03*
X95202Y290958D03*
X98565Y290455D03*
X102107Y290439D03*
X105603Y291092D03*
X95146Y279609D03*
X110808Y291075D03*
X98546Y279609D03*
X114915Y290203D03*
X104413Y278608D03*
X117027Y278475D03*
X148834Y284832D03*
X107750Y277953D03*
X128918Y307533D03*
X135308Y276806D03*
X139784Y276432D03*
X142241Y278783D03*
X95400Y383083D03*
X118744Y525279D03*
X140399Y525238D03*
X129199Y525271D03*
X107103Y525057D03*
X95599Y525026D03*
X84799Y524898D03*
X90878Y585185D03*
X85654Y659044D03*
X83960Y632636D03*
X83500Y653600D03*
Y640044D03*
X84900Y747900D03*
X90746Y712435D03*
X90947Y709040D03*
X91003Y705214D03*
X91130Y701741D03*
X85300Y755100D03*
X85000Y775900D03*
X84100Y769000D03*
X220131Y58163D03*
X197900Y82000D03*
X201237Y106350D03*
X210356Y99104D03*
X210680Y84396D03*
X201614Y89932D03*
X212028Y93512D03*
X152350Y131084D03*
X204849Y106438D03*
X200100Y101200D03*
X170302Y147100D03*
X158100Y166800D03*
X160311Y141680D03*
X219548Y174651D03*
X189600Y166700D03*
X189700Y170200D03*
X190018Y173586D03*
X188961Y162715D03*
X167015Y167633D03*
X163550Y179657D03*
X172645Y179104D03*
X177087Y178920D03*
X183120Y266103D03*
X183082Y271969D03*
X182853Y256107D03*
X183956Y261452D03*
X168010Y267909D03*
X219717Y211198D03*
X182177Y251208D03*
X154300Y227900D03*
X171200Y233000D03*
X185563Y245456D03*
X175064Y232857D03*
X185740Y240983D03*
X185502Y237383D03*
X152663Y272053D03*
X192284Y258847D03*
X150666Y243134D03*
X195698Y259749D03*
X196365Y256414D03*
X168324Y246397D03*
X171762Y258345D03*
X167894Y243024D03*
X167760Y239626D03*
X183043Y276658D03*
X183707Y289861D03*
X183653Y283162D03*
X184188Y340638D03*
X162135Y332650D03*
X185042Y286734D03*
X167051Y293752D03*
X188273Y285674D03*
X187118Y281963D03*
X163142Y294193D03*
X172818Y288683D03*
X216178Y411331D03*
X219144Y414536D03*
X195307Y355649D03*
X206775Y348954D03*
X173508Y348462D03*
X177715Y397471D03*
X212500Y395500D03*
X217800Y395900D03*
X206871Y397177D03*
X210042Y412265D03*
X175767Y380311D03*
X189073Y380379D03*
X185276Y380362D03*
X181242Y380481D03*
X197565Y380257D03*
X203379Y380312D03*
X169600Y380500D03*
X173864Y397677D03*
X213400Y434601D03*
X181980Y458681D03*
X210772Y431456D03*
X200453Y439066D03*
X203186Y451492D03*
X180445Y422567D03*
X176991Y463723D03*
X184750Y427953D03*
X208947Y443700D03*
X196803Y444462D03*
X201400Y434400D03*
X202764Y444274D03*
X190887Y424438D03*
X174500Y424100D03*
X182060Y443776D03*
X180313Y446694D03*
X176915Y446556D03*
X195400Y452051D03*
X208632Y457048D03*
X181034Y427967D03*
X177700Y427300D03*
X184399Y525203D03*
X195499D03*
X206699D03*
X217899Y525103D03*
X162615Y525220D03*
X173537D03*
X151684Y525258D03*
X210223Y501477D03*
X213500Y503600D03*
X219590Y740816D03*
X254498Y88487D03*
X251687Y98033D03*
X261830Y81230D03*
X241101D03*
X256928Y69301D03*
X241132Y85023D03*
X242488Y88466D03*
X223948Y174292D03*
X251700Y135484D03*
X231350Y222067D03*
X223129Y210901D03*
X224664Y293860D03*
X257400Y403206D03*
X239600Y405600D03*
X237800Y411200D03*
X226576Y401835D03*
X228243Y380358D03*
X231915Y380533D03*
X244928Y367685D03*
X238151Y356092D03*
X228510Y367624D03*
X240715Y380333D03*
X222269Y402278D03*
X228949Y410741D03*
X225421Y410908D03*
X269840Y386256D03*
X261300Y402355D03*
X275500Y415400D03*
X264124Y408219D03*
X258267Y408800D03*
X233400Y409700D03*
X255010Y367624D03*
X273554Y386722D03*
X223600Y456200D03*
X246502Y472752D03*
X255622Y461532D03*
X263000Y438800D03*
X260600Y435900D03*
X258299Y432800D03*
X250400Y440000D03*
X249600Y428100D03*
X237700Y458000D03*
X279120Y440440D03*
X276761Y443421D03*
X277575Y449398D03*
X270714Y458323D03*
X263719Y455536D03*
X259779Y456823D03*
X220768Y418393D03*
X260322Y462288D03*
X256852Y465331D03*
X258221Y469246D03*
X235069Y464940D03*
X257184Y421241D03*
X271342Y440630D03*
X235600Y433300D03*
X264775Y459236D03*
X279789Y432846D03*
X285565Y438912D03*
X250400Y473300D03*
X260481Y473769D03*
X253214Y469048D03*
X228400Y486400D03*
X228001Y474064D03*
X226000Y458700D03*
X249845Y469508D03*
X229300Y442500D03*
X225700Y496800D03*
X226115Y507011D03*
X229513Y507141D03*
X232912Y507242D03*
X224515Y532633D03*
X237336Y531828D03*
X236700Y539300D03*
X240400Y534500D03*
X245800D03*
X241300Y539300D03*
X236300Y535600D03*
X243200Y531700D03*
X288586Y493703D03*
X268215Y490733D03*
X251755Y491731D03*
X270700Y495400D03*
X274315Y497133D03*
X283657Y532832D03*
X280259Y532714D03*
X232200Y492100D03*
X231739Y495469D03*
X248286Y489208D03*
X242100Y489000D03*
X228500Y498900D03*
X281183Y592936D03*
X223671Y740896D03*
X223129Y764830D03*
X271970Y798668D03*
X282413Y798410D03*
X228021Y787335D03*
X223596Y782163D03*
X236973Y795418D03*
X235169Y791455D03*
X240130Y789012D03*
X305456Y481787D03*
X335532Y485626D03*
X323215Y485633D03*
X304783Y467192D03*
X295115Y476433D03*
Y473033D03*
X297715Y479588D03*
X306603Y459523D03*
X301437Y426833D03*
X304200Y432600D03*
X300603Y432406D03*
X297238Y429641D03*
X304550Y424222D03*
X300059Y422844D03*
X318015Y493833D03*
X334315Y496733D03*
X330815Y493433D03*
X327115Y489533D03*
X344815Y494933D03*
X321415Y497133D03*
X304000Y538500D03*
X308800Y540925D03*
X324400Y570500D03*
X346510Y796385D03*
X350765D03*
X315696Y798445D03*
X294148Y798547D03*
X305437Y798205D03*
X362793Y77815D03*
Y126096D03*
X381025Y73748D03*
Y120650D03*
X373496Y140021D03*
X365131Y135484D03*
X428343Y463067D03*
X420575Y467336D03*
X382695Y467033D03*
Y471133D03*
X388884Y468631D03*
X387143Y462647D03*
X416588Y467839D03*
X361814Y796557D03*
X500295Y401715D03*
X501800Y387600D03*
X473838Y385675D03*
X474106Y382285D03*
X473605Y389068D03*
X499764Y411324D03*
X497279Y382551D03*
X435138Y460661D03*
X457091Y486699D03*
X501700Y477200D03*
X483530Y541762D03*
X487073Y554094D03*
X482183Y535169D03*
X483008Y500529D03*
X469932Y518034D03*
X447307Y511890D03*
X447090Y497242D03*
X471410Y490049D03*
X498994Y488322D03*
X501802Y490240D03*
X523200Y399400D03*
X506100Y380000D03*
X517041Y388700D03*
X536928Y411324D03*
X514000Y486293D03*
X508306Y428179D03*
X504500Y479500D03*
X514073Y552477D03*
X503300Y539700D03*
X637200Y393900D03*
X629100Y536000D03*
X632600Y555200D03*
X636200Y555100D03*
X640100Y550600D03*
X662100Y394600D03*
X667979Y486293D03*
X702400Y431500D03*
X698300Y431600D03*
X702000Y485700D03*
X688615Y485133D03*
X707700Y476500D03*
X707890Y467821D03*
X684259Y476130D03*
X682774Y449737D03*
X667745Y456089D03*
X662604Y463284D03*
X671915Y543133D03*
X694700Y547700D03*
X688800Y540450D03*
X702400Y554800D03*
X705927Y538650D03*
X663600Y535395D03*
X644600Y556700D03*
X652400Y545200D03*
X674375Y509826D03*
X700512Y510204D03*
X643833Y549325D03*
X702000Y546581D03*
X702400Y550600D03*
X684600Y542100D03*
X682015Y493633D03*
X669200Y559600D03*
X656817Y567131D03*
X697600Y560000D03*
X701400Y560200D03*
X643100Y589900D03*
X689945Y758289D03*
X667982Y739870D03*
X681402Y757754D03*
X663575Y742289D03*
X668987Y731465D03*
X691075Y820814D03*
X680480Y773302D03*
X678755Y784815D03*
X676727Y790555D03*
X679630Y795856D03*
X680239Y802378D03*
X682693Y806283D03*
X684732Y810518D03*
X669886Y786112D03*
X666516Y784722D03*
X686308Y834802D03*
X646342Y826469D03*
X685799Y770894D03*
X690211Y827401D03*
X683715Y852233D03*
X710727Y862002D03*
X678351Y854383D03*
X679332Y841866D03*
X681156Y844982D03*
X681542Y848361D03*
X722687Y120650D03*
X727300Y273200D03*
X758200Y338900D03*
X756700Y370600D03*
X762900Y387400D03*
X729700Y551500D03*
X729600Y540400D03*
X724000Y532600D03*
X722682Y538700D03*
X716300Y517125D03*
X719800Y525000D03*
X719866Y528656D03*
X751965Y522097D03*
X747886D03*
X757848Y513543D03*
X752874Y534854D03*
X737297Y517903D03*
X756523Y520272D03*
X749493Y535216D03*
X725100Y519600D03*
X746000Y549700D03*
X726800Y527400D03*
X723538Y526440D03*
X742607Y549481D03*
X752100Y506500D03*
X749500Y508800D03*
X742000Y505000D03*
X762275Y512870D03*
X744073Y522097D03*
X755862Y516303D03*
X756400Y508100D03*
X756272Y534995D03*
X763000Y490800D03*
X717879Y564572D03*
X737400Y576200D03*
X766358Y564600D03*
X727700Y584400D03*
X758400Y568500D03*
X742600Y577100D03*
X757600Y639700D03*
X746669Y740179D03*
X743653Y744114D03*
X741453Y748054D03*
X738850Y751989D03*
X734450Y755929D03*
X730967Y759864D03*
X724305Y770450D03*
X723678Y774016D03*
X727477Y775212D03*
X724733Y779559D03*
X730028Y782297D03*
X724859Y784497D03*
X742663Y788885D03*
X729988Y787114D03*
X739510Y795264D03*
X725239Y788970D03*
X745230Y793211D03*
X729486Y791416D03*
X742370Y799077D03*
X725407Y794540D03*
X747659Y796960D03*
X744790Y802781D03*
X749593Y803991D03*
X747556Y808994D03*
X749629Y812608D03*
X722443Y826463D03*
X721704Y829981D03*
X724858Y831254D03*
X723801Y834857D03*
X726332Y837128D03*
X733066Y836450D03*
X729250Y850000D03*
X721243Y850725D03*
X718263Y863827D03*
X724093Y840187D03*
X726776Y842277D03*
X733796Y854172D03*
G54D17*
X22980Y59055D03*
X30854D03*
X22980Y106299D03*
Y98425D03*
Y90551D03*
Y82677D03*
Y74803D03*
Y66929D03*
X30854Y98425D03*
Y90551D03*
Y82677D03*
Y74803D03*
Y66929D03*
X41142Y135669D03*
Y155669D03*
Y145669D03*
X26181Y537559D03*
Y527559D03*
Y517559D03*
X41142Y655669D03*
Y645669D03*
Y635669D03*
Y763780D03*
Y753780D03*
Y773780D03*
G54D19*
X45700Y61000D03*
X65500Y60800D03*
X75500D03*
X45900Y50000D03*
X65700Y49800D03*
X50800Y39500D03*
X70700Y45800D03*
X55800Y61300D03*
X59900Y40600D03*
X50500Y67700D03*
X70500Y72000D03*
X60800Y72500D03*
X57200Y175300D03*
X39600Y494800D03*
X38200Y490900D03*
X35100Y494400D03*
X33600Y512600D03*
X37329Y524472D03*
X33880Y526500D03*
X33921Y520414D03*
X87900Y47800D03*
X90900Y42400D03*
X80400Y47800D03*
X147500Y90200D03*
X142167Y106366D03*
X142101Y98650D03*
X111100Y75500D03*
X100000Y75600D03*
X121700Y75300D03*
X85300Y70200D03*
X126300Y180209D03*
X126700Y173500D03*
X136291Y179968D03*
X136100Y173800D03*
X134200Y217300D03*
X130000Y217200D03*
X134600Y222200D03*
X209100Y51700D03*
X191700Y63300D03*
X209200Y65100D03*
X200700Y51700D03*
X185100Y55900D03*
X208900Y58600D03*
X192000Y55900D03*
X200700Y58300D03*
X184700Y63100D03*
X154500Y90000D03*
X158000Y79600D03*
X165200Y79500D03*
X163300Y95900D03*
X163500Y105500D03*
X151800Y72400D03*
X209000Y72300D03*
X201500D03*
X177100Y99500D03*
X177200Y104800D03*
X177300Y94200D03*
Y88500D03*
X184700D03*
X190700Y77800D03*
X201200Y65600D03*
X191000Y71300D03*
X184500Y71200D03*
X177400Y71400D03*
X177500Y77900D03*
X183700Y78100D03*
X191500Y88500D03*
X204200Y126700D03*
X206600Y130300D03*
X201900D03*
X282282Y47189D03*
X286930D03*
X228635Y385956D03*
X232788Y385893D03*
X229764Y513034D03*
X234416Y512963D03*
X238924Y512390D03*
X243100Y516300D03*
X245963Y511890D03*
X250975Y511729D03*
X255500Y514000D03*
X264000Y513400D03*
X299300Y41300D03*
X321300Y43200D03*
X351800Y42200D03*
X360500Y42600D03*
X330000Y42800D03*
X329900Y37100D03*
X321300D03*
X360500Y36700D03*
X291373Y47394D03*
X299300Y46400D03*
X351800Y36300D03*
X320207Y428442D03*
X320166Y432442D03*
X380956Y408290D03*
X376513Y408085D03*
X371865D03*
X380392Y416962D03*
X375949Y416757D03*
X371301D03*
X366653Y416484D03*
X367217Y407812D03*
X366719Y424200D03*
X371367Y424473D03*
X376015D03*
X380458Y424678D03*
X410200Y474200D03*
X410179Y469769D03*
X438300Y481200D03*
X434515Y483333D03*
X434412Y479334D03*
X432014Y476132D03*
X633923Y520400D03*
X711500Y438300D03*
X644900Y538300D03*
X726000Y650700D03*
X720000Y650800D03*
X733000Y650600D03*
X740000D03*
X745413Y854763D03*
G54D22*
X54724Y557087D03*
Y620079D03*
Y675197D03*
Y738189D03*
X144843Y798779D03*
Y874449D03*
G54D26*
X276982Y828335D03*
X286982Y818335D03*
X276982D03*
X356982D03*
X346982D03*
X336982D03*
X326982D03*
X316982D03*
X306982D03*
X296982D03*
X366982D03*
G54D24*
X144843Y812994D03*
Y860234D03*
G54D16*
X6614Y553544D03*
X10551Y623622D03*
X6614Y671654D03*
X10551Y741732D03*
X18425Y553544D03*
X32204D03*
X18425Y623622D03*
X32204D03*
X18425Y671654D03*
X32204D03*
X18425Y741732D03*
X32204D03*
G54D27*
X314000Y405200D03*
X316800Y415900D03*
X299800Y398500D03*
X332600Y400100D03*
X413900Y396400D03*
X414894Y453432D03*
X419296Y449111D03*
X423572Y453454D03*
X419092Y457572D03*
X419225Y453324D03*
X428616Y429466D03*
X391500Y459000D03*
X399900Y458600D03*
X421273Y439381D03*
X475600Y462100D03*
X452300Y420900D03*
X458900Y446600D03*
X483100Y449900D03*
X488500Y474200D03*
X450300Y459900D03*
X471300Y482200D03*
X449000Y480000D03*
X438316Y449493D03*
X438294Y453811D03*
G54D11*
X-138100Y222300D03*
Y241300D03*
Y260300D03*
Y279300D03*
Y298300D03*
Y317300D03*
Y336300D03*
X-70100Y222300D03*
X-87100D03*
X-104100D03*
X-121100D03*
X-70100Y241300D03*
X-87100D03*
X-104100D03*
X-121100D03*
X-70100Y260300D03*
X-87100D03*
X-104100D03*
X-121100D03*
X-70100Y279300D03*
X-87100D03*
X-104100D03*
X-121100D03*
X-70100Y298300D03*
X-87100D03*
X-104100D03*
X-121100D03*
X-70100Y317300D03*
X-87100D03*
X-104100D03*
X-121100D03*
X-70100Y336300D03*
X-87100D03*
X-104100D03*
X-121100D03*
X4800Y48600D03*
X5800Y6400D03*
X5000Y71900D03*
Y91900D03*
X5100Y111800D03*
X4900Y130400D03*
X5000Y150500D03*
X5300Y170000D03*
X-2100Y222300D03*
X-19100D03*
X-36100D03*
X-53100D03*
X-2100Y241300D03*
X-19100D03*
X-36100D03*
X-53100D03*
X-2100Y260300D03*
X-19100D03*
X-36300Y260000D03*
X-53100Y260300D03*
X-1900Y288300D03*
X-49400Y284500D03*
X-19600Y279500D03*
X-36100Y279300D03*
X-2100Y298300D03*
X-19100D03*
X-36100D03*
X-53100D03*
X-2100Y317300D03*
X-19100D03*
X-36100D03*
X-53100D03*
X-2100Y336300D03*
X-19100D03*
X-36100D03*
X-53100D03*
X-1600Y413600D03*
Y394600D03*
Y375600D03*
Y356600D03*
X-52600Y413600D03*
X-35600D03*
X-18600D03*
X-52600Y394600D03*
X-35600D03*
X-18600D03*
X-52600Y375600D03*
X-35600D03*
X-18600D03*
X-52600Y356600D03*
X-35600D03*
X-18600D03*
X-19400Y483400D03*
X-2400D03*
X-36400D03*
X-53400D03*
X-1500Y470300D03*
Y451300D03*
Y432300D03*
X-52500Y470300D03*
X-35500D03*
X-18500D03*
X-52500Y451300D03*
X-35500D03*
X-18500D03*
X-52500Y432300D03*
X-35500D03*
X-18500D03*
X9151Y473051D03*
X8672Y487593D03*
X-19400Y502400D03*
X-2400D03*
X-36400D03*
X-53400D03*
X7075Y527972D03*
X7927Y509647D03*
X8140Y637282D03*
X8246Y771416D03*
X53200Y26300D03*
X50600Y6000D03*
X48100Y133900D03*
X59200Y95573D03*
X47900Y145500D03*
X48100Y153800D03*
X43800Y204800D03*
X38800Y194300D03*
X38700Y199700D03*
X73700D03*
X49500Y169300D03*
X61751Y181464D03*
X44100Y200600D03*
X49286Y203671D03*
X69000Y202700D03*
X77200Y189000D03*
X60200Y193550D03*
X43900Y209000D03*
X72001Y265901D03*
X69400Y207400D03*
X43181Y278603D03*
X39563Y307968D03*
X21876Y282289D03*
X41418Y287473D03*
X70775Y398396D03*
X70845Y405839D03*
X70952Y414050D03*
X54515Y396433D03*
X54463Y386651D03*
X70865Y390502D03*
X43569Y379314D03*
X65605Y367307D03*
X16158Y477255D03*
X79050Y457367D03*
X74805Y481031D03*
X66991Y476766D03*
X62798Y461555D03*
X74451Y465323D03*
X79094Y441620D03*
X74801Y433368D03*
X70869Y421840D03*
X70759Y449277D03*
X20715Y485712D03*
X20276Y477090D03*
X18809Y491871D03*
X17212Y532250D03*
X18064Y513925D03*
X78742Y488905D03*
X66961Y488885D03*
X74805Y492842D03*
X56121Y494271D03*
X21090Y497108D03*
X54659Y513125D03*
X67140Y511501D03*
X50893Y534434D03*
X66300Y548000D03*
X69569Y594959D03*
X69520Y560987D03*
X68421Y570392D03*
X69323Y579887D03*
X69518Y604727D03*
X69220Y614992D03*
X18277Y641560D03*
X9844Y658803D03*
X19981Y663081D03*
X68928Y687846D03*
X69316Y697605D03*
X69911Y676938D03*
X73900Y664900D03*
X77000Y646200D03*
X72930Y645818D03*
X67257Y643668D03*
X9631Y753837D03*
X19768Y758115D03*
X69558Y711913D03*
X68620Y722610D03*
X69217Y732676D03*
X73325Y760926D03*
X67809Y758190D03*
X18383Y775694D03*
X55459Y780063D03*
X48300Y775300D03*
X73282Y778907D03*
X124100Y6700D03*
X110800Y48800D03*
X120200Y48400D03*
X98700Y48900D03*
X143900Y38000D03*
X108100Y35300D03*
X146900Y48500D03*
X109700Y6400D03*
X119700Y35400D03*
X139800Y31100D03*
X96300Y6100D03*
X147200Y7300D03*
X108600Y19900D03*
X126500Y20100D03*
X82400Y89500D03*
X79900Y148700D03*
X103300Y160900D03*
X112000Y160700D03*
X119900Y162200D03*
X125300Y162300D03*
X122100Y203300D03*
X96900Y189286D03*
X107771Y182699D03*
X145400Y161955D03*
X114700Y157000D03*
X107672Y156597D03*
X98700Y156200D03*
X122200Y156700D03*
X80207Y139965D03*
X81200Y176000D03*
X125600Y221200D03*
X113863Y228669D03*
X102559Y228575D03*
X97885Y228339D03*
X147013Y225483D03*
X122000Y207300D03*
X94600Y206900D03*
X94548Y211258D03*
X106419Y310245D03*
X126184Y310860D03*
X93200Y308800D03*
X121477Y314973D03*
X135613Y308903D03*
X145795Y410173D03*
X149431Y394402D03*
X149783Y390487D03*
X110238Y410161D03*
X141738Y414098D03*
X133863Y413773D03*
X114175Y414098D03*
X122053D03*
X125990Y410161D03*
X94579Y406324D03*
X118130Y398511D03*
X98427Y410161D03*
X90553Y414098D03*
X86563Y402383D03*
X133964Y394555D03*
X102555Y394412D03*
X86616Y394413D03*
X86463Y390483D03*
X84200Y380000D03*
X145675Y473157D03*
Y465283D03*
X149719Y457328D03*
X129927Y473157D03*
Y465283D03*
X137801Y461346D03*
Y457409D03*
X114175Y473157D03*
X122053Y469220D03*
X110263Y469083D03*
X122053Y473157D03*
X90350Y473069D03*
X82679Y477094D03*
X90662Y461604D03*
X106263Y453483D03*
X106449Y465157D03*
X122053Y445598D03*
X126180Y418224D03*
X137801Y437720D03*
X137767Y425993D03*
X129927Y445598D03*
X141738Y449535D03*
X133864Y421972D03*
Y429846D03*
X98533Y418180D03*
X118134Y449362D03*
X106363Y441583D03*
X110238Y445598D03*
X110289Y422113D03*
X122053Y437720D03*
X114175D03*
X94661Y441681D03*
X106263Y433683D03*
X90544Y433408D03*
X90408Y421930D03*
X129927Y437720D03*
X141738Y488905D03*
X110238D03*
X125990D03*
X94377Y489070D03*
X91852Y563129D03*
X91156Y572112D03*
X90823Y581387D03*
X91343Y598284D03*
X91023Y606587D03*
X90923Y616187D03*
X90681Y690157D03*
X90174Y678675D03*
X85600Y647837D03*
X106051Y767209D03*
X93840Y699686D03*
X90814Y734451D03*
X91027Y724985D03*
X91094Y715818D03*
X84703Y758885D03*
X84182Y764879D03*
X122899Y825236D03*
X112762Y820958D03*
X116188Y771487D03*
X131900Y893200D03*
X120874Y857517D03*
X110737Y853239D03*
X131700Y915700D03*
X89871Y917500D03*
X173200Y10900D03*
X213700Y35200D03*
X186000D03*
X197796Y12653D03*
X160600Y49100D03*
X153200Y48700D03*
X167500Y49000D03*
X160500Y19700D03*
X170400Y31100D03*
X150600Y37800D03*
X212800Y125800D03*
X182400Y128300D03*
X175598Y128436D03*
X220100Y123600D03*
X166700Y128800D03*
X172200Y128300D03*
X179000D03*
X205628Y89404D03*
X211700Y181600D03*
X208200Y153500D03*
X203900D03*
X200100Y146500D03*
Y150400D03*
X199100Y153800D03*
X194800D03*
X207495Y192761D03*
X169800Y155796D03*
X165162Y155909D03*
X169709Y160049D03*
X165388Y160094D03*
X174339Y151172D03*
X178400Y152300D03*
X156800Y230500D03*
X152663Y267791D03*
X216335Y218212D03*
X196344Y237383D03*
X196078Y248183D03*
X196021Y244556D03*
X196151Y240983D03*
X151519Y250193D03*
X180641Y231683D03*
X186319Y268076D03*
X183466Y294017D03*
X152580Y285530D03*
X203410Y394323D03*
X182378Y390377D03*
X157574Y394185D03*
X161241Y398226D03*
X161277Y414114D03*
X174124Y402624D03*
X161213Y390551D03*
X169503Y386977D03*
X200161Y416474D03*
X206142Y413945D03*
X211243Y462005D03*
X161423Y484968D03*
Y481031D03*
X157486Y473157D03*
X165360Y469220D03*
X153549Y477094D03*
X173234Y465283D03*
Y453472D03*
X203406Y454885D03*
X174086Y484839D03*
X195038Y477148D03*
X175150Y476294D03*
X174351Y429014D03*
X161423Y437720D03*
X153549Y433783D03*
X161363Y425780D03*
X173234Y437720D03*
X173155Y417978D03*
X153422Y441722D03*
X216300Y499600D03*
X157486Y488905D03*
X165360D03*
X169297Y492842D03*
X161423D03*
X193016Y496643D03*
X219492Y517832D03*
X196400Y585300D03*
X179000Y624800D03*
X193600Y702400D03*
X179100Y714600D03*
X202300Y742000D03*
X157422Y825918D03*
X158725Y835536D03*
X181642Y837321D03*
Y827853D03*
X181772Y818429D03*
X159926Y813000D03*
X201663Y827680D03*
X201142Y837191D03*
X189273Y902478D03*
X213138Y905780D03*
X218729Y857629D03*
X160735Y857183D03*
X154730Y847010D03*
X181081Y856307D03*
X181124Y847013D03*
X200798Y846849D03*
X200460Y913771D03*
X233900Y32500D03*
X266700Y46900D03*
X263000Y47000D03*
X257500Y46900D03*
X253800Y47000D03*
X244900Y47300D03*
X248600Y47200D03*
X252187Y23895D03*
X286651Y14571D03*
X224431Y15210D03*
X248900Y8400D03*
X235000Y47500D03*
X238700Y47400D03*
X225231Y58420D03*
X282444Y106834D03*
X225919Y88394D03*
X225937Y80731D03*
X221710Y80767D03*
X221722Y88431D03*
X230158Y88359D03*
X230123Y80805D03*
X225851Y73774D03*
X221740Y73844D03*
X229870Y73970D03*
X228169Y68374D03*
X224169Y68520D03*
X228728Y96613D03*
X224285Y96750D03*
X259815Y94233D03*
X248000Y114500D03*
X246100Y151300D03*
Y155800D03*
Y160400D03*
X258741Y193852D03*
X231049Y188760D03*
X256823Y221979D03*
X246169Y246270D03*
X230774Y270268D03*
X241694Y274956D03*
X238614Y217763D03*
X222496Y222320D03*
X239693Y396029D03*
X257500Y399300D03*
X264600Y380500D03*
X270800Y408500D03*
X269300Y486200D03*
X249600Y432500D03*
X239000Y440300D03*
X244800Y454500D03*
X229600Y460700D03*
X289200Y445100D03*
X252200Y486700D03*
X290300Y462400D03*
X290011Y456234D03*
X289000Y449200D03*
X221035Y453935D03*
X268600Y529800D03*
X256300Y531400D03*
X289400Y511700D03*
X243300Y527900D03*
X247256Y529218D03*
X251700Y531500D03*
X268500Y525800D03*
X238118Y492166D03*
X246132Y492160D03*
X289405Y515437D03*
X277300Y572500D03*
X259600Y568400D03*
X271949Y648699D03*
X272588Y681087D03*
X244248Y682153D03*
X255542Y665532D03*
X241904Y652321D03*
X289634Y659352D03*
X284520Y743307D03*
X282176Y713475D03*
X228249Y761450D03*
X230823Y823850D03*
X237950Y774979D03*
X237815Y779065D03*
X226949Y782735D03*
X253623Y867319D03*
X254262Y899707D03*
X225922Y900773D03*
X237216Y884152D03*
X223578Y870941D03*
X285585Y897363D03*
X283241Y867531D03*
X264212Y903112D03*
X277254Y852624D03*
X299600Y62100D03*
X351900Y62000D03*
X360200Y62300D03*
X329500Y62600D03*
X321300Y63100D03*
X325006Y15636D03*
X299500Y68200D03*
X352000Y68000D03*
X360200Y68200D03*
X329600D03*
X321400Y68500D03*
X344663Y108965D03*
X312275Y98098D03*
X354197Y158187D03*
X301140Y161383D03*
X352066Y262596D03*
X307320Y223390D03*
X301781Y258122D03*
X322022Y279856D03*
X309200Y444700D03*
X331800Y440400D03*
X331900Y444600D03*
X356700Y437500D03*
X348800D03*
X341500Y437400D03*
X291300Y468600D03*
X308900Y449100D03*
X327900Y438100D03*
X341430Y459351D03*
X345735Y460843D03*
X349800Y460000D03*
X353698Y460323D03*
X357812Y460406D03*
X350400Y512000D03*
X335600Y511400D03*
X304700Y509500D03*
X317900Y520100D03*
X314628Y517729D03*
X343905Y519116D03*
X309648Y582024D03*
X319679Y655730D03*
X320318Y688118D03*
X291978Y689184D03*
X303272Y672563D03*
X347378Y688332D03*
X358672Y671711D03*
X345034Y658500D03*
X302115Y693462D03*
X360803Y704312D03*
X333102Y737766D03*
X344396Y721145D03*
X330758Y707934D03*
X312221Y709853D03*
X312860Y742241D03*
X295814Y726686D03*
X319171Y767846D03*
X313959Y724732D03*
X354623Y896937D03*
X352279Y867105D03*
X313286Y863909D03*
X313925Y896297D03*
X296879Y880742D03*
X332436Y858576D03*
X337648Y901690D03*
X382100Y61900D03*
X401343Y58465D03*
X394098Y20059D03*
X362775D03*
X412506Y33484D03*
X382200Y68500D03*
X410025Y87658D03*
X390208Y180135D03*
X366982Y198886D03*
X407769Y204757D03*
X384668Y247681D03*
X376144Y279856D03*
X378700Y437600D03*
X371200Y437800D03*
X363800Y437700D03*
X361533Y460222D03*
X365241Y460010D03*
X375079Y654878D03*
X375718Y687266D03*
X430267Y679595D03*
X413860Y696428D03*
X400222Y683217D03*
X388817Y692040D03*
X420252Y725194D03*
X420891Y757582D03*
X392551Y758648D03*
X403845Y742027D03*
X390207Y728816D03*
X361442Y736700D03*
X430906Y711983D03*
X402566Y713049D03*
X395450Y767846D03*
X378868Y723311D03*
X421530Y814262D03*
X419186Y784430D03*
X429202Y894806D03*
X426858Y864974D03*
X382324Y863483D03*
X382963Y895871D03*
X365917Y880316D03*
X413927Y901690D03*
X397345Y857155D03*
X432682Y23909D03*
X472315Y23056D03*
X496393Y55871D03*
X457399Y46069D03*
X496109Y93412D03*
X457989Y78967D03*
X493200Y145500D03*
X451789Y154565D03*
X473097Y208901D03*
X453252Y250240D03*
X500526Y394177D03*
X494400Y493600D03*
Y497500D03*
X455846Y546626D03*
X471650Y493916D03*
X494410Y501344D03*
X458713Y518034D03*
X482200Y529100D03*
X484200Y538000D03*
X483800Y545700D03*
X452652Y495705D03*
X465900Y501200D03*
X465212Y726260D03*
X465851Y758648D03*
X437511Y759714D03*
X448805Y743093D03*
X435167Y729882D03*
X474587Y765253D03*
X445197Y719047D03*
X449231Y780808D03*
X449870Y813196D03*
X432824Y797641D03*
X476931Y795085D03*
X488225Y778464D03*
X499945Y828325D03*
X486307Y815114D03*
X456903Y861352D03*
X457542Y893740D03*
X440496Y878185D03*
X488651Y844946D03*
X499208Y899795D03*
X463674Y852891D03*
X557547Y24335D03*
X526213Y34431D03*
X555558Y100229D03*
X531425Y77545D03*
X545330Y147959D03*
X521476Y205704D03*
X509632Y174434D03*
X526688Y248818D03*
X513500Y399060D03*
X520900Y388100D03*
X523462Y423957D03*
X503923Y423910D03*
X536736Y418540D03*
X529000Y550500D03*
X566000Y536700D03*
X502318Y535328D03*
X521002Y555911D03*
X525300Y552800D03*
X516900Y561200D03*
X528000Y562900D03*
X512700Y560000D03*
X508224Y580873D03*
X549379Y653173D03*
X504632Y761631D03*
X505271Y794019D03*
X516352Y811492D03*
X562377Y833013D03*
X532332Y836635D03*
X516991Y843880D03*
X563016Y865401D03*
X534676Y866467D03*
X545970Y849846D03*
X545118Y880530D03*
X528711Y897363D03*
X515073Y884152D03*
X562590Y881808D03*
X510579Y854786D03*
X545757Y912918D03*
X517417Y913984D03*
X564934Y911640D03*
X573457Y59531D03*
X621826Y20111D03*
X591122Y33010D03*
X607704Y77545D03*
X586385Y204283D03*
X596334Y173012D03*
X602967Y248818D03*
X638300Y511800D03*
X641800Y519000D03*
X639500Y521900D03*
X641700Y510300D03*
X587942Y582024D03*
X614582Y653599D03*
X604141Y675547D03*
X578784Y682152D03*
X582620Y653386D03*
X632693Y697281D03*
X607550Y703460D03*
X628006Y720720D03*
X592635Y878186D03*
X576228Y895019D03*
X640791Y876268D03*
X641430Y908656D03*
X613090Y909722D03*
X624384Y893101D03*
X610746Y879890D03*
X593274Y910574D03*
X660180Y56547D03*
X657451Y28746D03*
X703700Y30300D03*
X651658Y95968D03*
X692985Y75650D03*
X699619Y201914D03*
X652714Y200019D03*
X692512Y162589D03*
X661673Y260892D03*
X688248Y246923D03*
X712386Y297542D03*
X693509Y431701D03*
X689111Y431612D03*
X684869Y431611D03*
X680738Y431633D03*
X651000Y467700D03*
X646163Y482677D03*
X643296Y477617D03*
X643914Y470592D03*
X648652Y470028D03*
X654990Y463513D03*
X658399Y460842D03*
X659485Y455066D03*
X666818Y452921D03*
X694995Y453626D03*
X694923Y461253D03*
X694851Y469456D03*
X694907Y476993D03*
X710645Y447266D03*
X678767Y447136D03*
X672583Y467901D03*
X667831Y479556D03*
X711409Y467621D03*
X665499Y556600D03*
X651800Y540295D03*
X711400Y515400D03*
X711900Y521500D03*
X675400Y538100D03*
X662200Y547300D03*
X709600Y524100D03*
X668135Y523360D03*
X672161Y528021D03*
X676550Y523677D03*
X672342Y519560D03*
X672257Y523769D03*
X658314Y526697D03*
X672168Y538889D03*
X676115Y542633D03*
X685815Y496140D03*
X689996Y496274D03*
X694169Y496394D03*
X698475Y496387D03*
X702670Y496148D03*
X707296Y496348D03*
X712102Y542133D03*
X707589Y515400D03*
X700900Y539500D03*
X707391Y564566D03*
X678293Y698772D03*
X675736Y657222D03*
X694061Y681726D03*
X654641Y691101D03*
X643987Y664041D03*
X697897Y662763D03*
X708231Y730948D03*
X681276Y722211D03*
X650805Y716671D03*
X698962Y707936D03*
X700989Y759255D03*
X711116Y796516D03*
X702290Y820921D03*
X692356Y875629D03*
X692995Y908017D03*
X664655Y909083D03*
X675949Y892462D03*
X662311Y879251D03*
X754800Y56800D03*
Y36800D03*
Y16800D03*
X723466Y60810D03*
X721334Y17767D03*
X754800Y76800D03*
X754700Y117600D03*
Y97600D03*
X734333Y88085D03*
X754700Y197600D03*
Y177600D03*
Y157600D03*
Y137600D03*
Y257600D03*
Y237600D03*
Y217600D03*
Y277600D03*
X753800Y303200D03*
X767300Y340400D03*
X766900Y333754D03*
X735134Y289819D03*
X767000Y410900D03*
X766700Y403500D03*
X766900Y395400D03*
Y387800D03*
Y364600D03*
Y356300D03*
X767600Y348500D03*
X716700Y445400D03*
X742200Y472500D03*
X724300Y454000D03*
X719100Y478900D03*
X767400Y481600D03*
Y465900D03*
X767500Y450800D03*
X767300Y441747D03*
X766500Y435100D03*
X766800Y427000D03*
X767100Y418700D03*
X744986Y481255D03*
X749974Y477780D03*
X749628Y471196D03*
X739751Y469686D03*
X735295Y463720D03*
X738636Y457903D03*
X731780Y452531D03*
X729478Y459116D03*
X721600Y451000D03*
X719700Y485600D03*
X768000Y457700D03*
X767700Y473300D03*
X767100Y544600D03*
X766800Y535700D03*
X767200Y524500D03*
X766900Y497700D03*
X767200Y489700D03*
X767100Y623900D03*
Y614800D03*
X766700Y606900D03*
X767700Y600200D03*
X766700Y592700D03*
X767000Y584300D03*
Y576100D03*
Y569500D03*
X725900Y561800D03*
X766900Y639500D03*
Y631900D03*
X715795Y697494D03*
X750300Y663000D03*
X740513Y687906D03*
X756100Y658700D03*
X745733Y713048D03*
X764200Y813000D03*
X716221Y876694D03*
X729859Y889905D03*
X718565Y906526D03*
X746905Y905460D03*
X746266Y873072D03*
X745100Y859405D03*
X721112Y854419D03*
G54D18*
X29528Y19685D03*
X76772D03*
X108268Y905512D03*
X155512D03*
G54D21*
X53547Y322486D03*
Y302486D03*
X182681Y580832D03*
Y560832D03*
G54D13*
X-33503Y269685D03*
G54D28*
X716535Y39370D03*
G54D10*
X-1011811Y-15748D03*
Y940945D03*
X775591Y-15748D03*
Y940944D03*
G54D12*
X-59094Y277559D03*
X-7913D03*
G54D20*
X30854Y106299D03*
G54D25*
X286982Y828335D03*
X356982D03*
X346982D03*
X336982D03*
X326982D03*
X316982D03*
X306982D03*
X296982D03*
X366982D03*
G54D23*
X109410Y796831D03*
Y876397D03*
X168465Y796831D03*
Y876397D03*
%LPC*%
G75*
G54D30*
G01X-755164Y-252763D02*
Y-235263D01*
G01X-746868D02*
X-755164Y-246055D01*
G01X-745558Y-252763D02*
X-751453Y-241097D01*
G01X-737883Y-252763D02*
Y-235263D01*
X-727839Y-252763D01*
Y-235263D01*
G01X-715361Y-252763D02*
X-717108Y-252471D01*
X-718636Y-251305D01*
X-719946Y-249555D01*
X-720820Y-247513D01*
X-721256Y-245180D01*
Y-242846D01*
X-720820Y-240513D01*
X-719946Y-238471D01*
X-718636Y-236722D01*
X-717108Y-235555D01*
X-715361Y-235263D01*
X-713615Y-235555D01*
X-712086Y-236722D01*
X-710776Y-238471D01*
X-709902Y-240513D01*
X-709466Y-242846D01*
Y-245180D01*
X-709902Y-247513D01*
X-710776Y-249555D01*
X-712086Y-251305D01*
X-713615Y-252471D01*
X-715361Y-252763D01*
G01X-702446D02*
X-693276Y-235263D01*
G01X-702446D02*
X-693276Y-252763D01*
G01X-658494D02*
X-667228D01*
Y-235263D01*
X-658494D01*
G01X-661988Y-243721D02*
X-667228D01*
G01X-649946Y-252763D02*
X-640776Y-235263D01*
G01X-649946D02*
X-640776Y-252763D01*
G01X-632228D02*
Y-235263D01*
X-626988D01*
X-625241Y-236138D01*
X-623931Y-238180D01*
X-623494Y-240513D01*
X-623931Y-242846D01*
X-625023Y-244596D01*
X-626988Y-245472D01*
X-632228D01*
G01X-615820Y-252763D02*
X-610361Y-235263D01*
X-604902Y-252763D01*
G01X-606868Y-246638D02*
X-613855D01*
G01X-597883Y-252763D02*
Y-235263D01*
X-587839Y-252763D01*
Y-235263D01*
G01X-580164Y-252763D02*
Y-235263D01*
X-575798D01*
X-574051Y-236138D01*
X-572741Y-237305D01*
X-571649Y-239054D01*
X-570776Y-241097D01*
X-570558Y-244013D01*
X-570776Y-246930D01*
X-571649Y-248972D01*
X-572741Y-250722D01*
X-574051Y-251888D01*
X-575798Y-252763D01*
X-580164D01*
G01X-553494D02*
X-562228D01*
Y-235263D01*
X-553494D01*
G01X-556988Y-243721D02*
X-562228D01*
G01X-544728Y-252763D02*
Y-235263D01*
X-539269D01*
X-537523Y-236138D01*
X-536431Y-237305D01*
X-535994Y-239638D01*
X-536431Y-241972D01*
X-537741Y-243430D01*
X-539269Y-244305D01*
X-544728D01*
G01X-539269D02*
X-535994Y-252763D01*
G01X-503615Y-243430D02*
X-502741Y-242555D01*
X-502086Y-241097D01*
X-501649Y-239054D01*
X-502086Y-237305D01*
X-502959Y-236138D01*
X-504488Y-235263D01*
X-510383D01*
Y-252763D01*
X-503178D01*
X-501649Y-251597D01*
X-500776Y-249846D01*
X-500339Y-247805D01*
X-500776Y-245763D01*
X-502086Y-244013D01*
X-503615Y-243430D01*
X-510383D01*
G01X-487861Y-252763D02*
X-489608Y-252471D01*
X-491136Y-251305D01*
X-492446Y-249555D01*
X-493320Y-247513D01*
X-493756Y-245180D01*
Y-242846D01*
X-493320Y-240513D01*
X-492446Y-238471D01*
X-491136Y-236722D01*
X-489608Y-235555D01*
X-487861Y-235263D01*
X-486115Y-235555D01*
X-484586Y-236722D01*
X-483276Y-238471D01*
X-482402Y-240513D01*
X-481966Y-242846D01*
Y-245180D01*
X-482402Y-247513D01*
X-483276Y-249555D01*
X-484586Y-251305D01*
X-486115Y-252471D01*
X-487861Y-252763D01*
G01X-475820D02*
X-470361Y-235263D01*
X-464902Y-252763D01*
G01X-466868Y-246638D02*
X-473855D01*
G01X-457228Y-252763D02*
Y-235263D01*
X-451769D01*
X-450023Y-236138D01*
X-448931Y-237305D01*
X-448494Y-239638D01*
X-448931Y-241972D01*
X-450241Y-243430D01*
X-451769Y-244305D01*
X-457228D01*
G01X-451769D02*
X-448494Y-252763D01*
G01X-440164D02*
Y-235263D01*
X-435798D01*
X-434051Y-236138D01*
X-432741Y-237305D01*
X-431649Y-239054D01*
X-430776Y-241097D01*
X-430558Y-244013D01*
X-430776Y-246930D01*
X-431649Y-248972D01*
X-432741Y-250722D01*
X-434051Y-251888D01*
X-435798Y-252763D01*
X-440164D01*
G01X-633538Y-207763D02*
Y-190263D01*
X-627861Y-204846D01*
X-622184Y-190263D01*
Y-207763D01*
G01X-610361D02*
X-611671Y-207471D01*
X-612981Y-206305D01*
X-613855Y-204263D01*
X-614291Y-201930D01*
X-613855Y-199596D01*
X-612981Y-197555D01*
X-611671Y-196388D01*
X-610361Y-196097D01*
X-609051Y-196388D01*
X-607741Y-197555D01*
X-606868Y-199596D01*
X-606649Y-201930D01*
X-606868Y-204263D01*
X-607741Y-206305D01*
X-609051Y-207471D01*
X-610361Y-207763D01*
G01X-588931Y-190263D02*
Y-207763D01*
G01Y-205139D02*
X-589804Y-206597D01*
X-591115Y-207471D01*
X-592643Y-207763D01*
X-594389Y-207180D01*
X-595699Y-205722D01*
X-596573Y-203972D01*
X-596791Y-201930D01*
X-596573Y-199888D01*
X-595699Y-198138D01*
X-594389Y-196680D01*
X-592643Y-196097D01*
X-591115Y-196388D01*
X-590023Y-196972D01*
X-588931Y-198138D01*
G01X-578636Y-199888D02*
X-571649D01*
X-572304Y-197846D01*
X-573396Y-196680D01*
X-574924Y-196097D01*
X-576453Y-196388D01*
X-577763Y-197263D01*
X-578636Y-199305D01*
X-579073Y-201055D01*
Y-202805D01*
X-578636Y-204555D01*
X-577544Y-206305D01*
X-576234Y-207471D01*
X-574706Y-207763D01*
X-573178Y-207180D01*
X-571649Y-205430D01*
G01X-557861Y-207763D02*
Y-190263D01*
G01X-380161Y-252763D02*
Y-235263D01*
X-382781Y-238763D01*
G01Y-252763D02*
X-377541D01*
G01X-366809Y-238180D02*
X-365499Y-236430D01*
X-363971Y-235555D01*
X-362224Y-235263D01*
X-360041Y-235846D01*
X-358513Y-237305D01*
X-358076Y-239054D01*
X-358294Y-240805D01*
X-359168Y-242263D01*
X-363534Y-245180D01*
X-365499Y-247221D01*
X-366809Y-250139D01*
X-367246Y-252763D01*
X-358076D01*
G01X-345161Y-235263D02*
X-346908Y-235846D01*
X-348218Y-237305D01*
X-349091Y-239054D01*
X-349746Y-241388D01*
X-349964Y-244013D01*
X-349746Y-246638D01*
X-349091Y-248972D01*
X-348218Y-250722D01*
X-346908Y-252180D01*
X-345161Y-252763D01*
X-343415Y-252180D01*
X-342104Y-250722D01*
X-341231Y-248972D01*
X-340576Y-246638D01*
X-340358Y-244013D01*
X-340576Y-241388D01*
X-341231Y-239054D01*
X-342104Y-237305D01*
X-343415Y-235846D01*
X-345161Y-235263D01*
G01X-327661D02*
X-329408Y-235846D01*
X-330718Y-237305D01*
X-331591Y-239054D01*
X-332246Y-241388D01*
X-332464Y-244013D01*
X-332246Y-246638D01*
X-331591Y-248972D01*
X-330718Y-250722D01*
X-329408Y-252180D01*
X-327661Y-252763D01*
X-325915Y-252180D01*
X-324604Y-250722D01*
X-323731Y-248972D01*
X-323076Y-246638D01*
X-322858Y-244013D01*
X-323076Y-241388D01*
X-323731Y-239054D01*
X-324604Y-237305D01*
X-325915Y-235846D01*
X-327661Y-235263D01*
G01X-307541Y-252763D02*
Y-235263D01*
X-315620Y-247805D01*
X-304702D01*
G01X-393278Y-207763D02*
Y-190263D01*
X-388038D01*
X-386291Y-191138D01*
X-384981Y-193180D01*
X-384544Y-195513D01*
X-384981Y-197846D01*
X-386073Y-199596D01*
X-388038Y-200472D01*
X-393278D01*
G01X-366608Y-191722D02*
X-367918Y-190846D01*
X-369446Y-190263D01*
X-371193D01*
X-373158Y-191138D01*
X-374686Y-192596D01*
X-375778Y-194347D01*
X-376651Y-197263D01*
X-376870Y-199888D01*
X-376433Y-202513D01*
X-375778Y-204263D01*
X-374468Y-206013D01*
X-372939Y-207180D01*
X-371411Y-207763D01*
X-369883D01*
X-368354Y-207180D01*
X-367044Y-206305D01*
X-365952Y-205139D01*
G01X-352165Y-198430D02*
X-351291Y-197555D01*
X-350636Y-196097D01*
X-350199Y-194054D01*
X-350636Y-192305D01*
X-351509Y-191138D01*
X-353038Y-190263D01*
X-358933D01*
Y-207763D01*
X-351728D01*
X-350199Y-206597D01*
X-349326Y-204846D01*
X-348889Y-202805D01*
X-349326Y-200763D01*
X-350636Y-199013D01*
X-352165Y-198430D01*
X-358933D01*
G01X-342961Y-213596D02*
X-329861D01*
G01X-323933Y-207763D02*
Y-190263D01*
X-313889Y-207763D01*
Y-190263D01*
G01X-301411Y-207763D02*
X-303158Y-207471D01*
X-304686Y-206305D01*
X-305996Y-204555D01*
X-306870Y-202513D01*
X-307306Y-200180D01*
Y-197846D01*
X-306870Y-195513D01*
X-305996Y-193471D01*
X-304686Y-191722D01*
X-303158Y-190555D01*
X-301411Y-190263D01*
X-299665Y-190555D01*
X-298136Y-191722D01*
X-296826Y-193471D01*
X-295952Y-195513D01*
X-295516Y-197846D01*
Y-200180D01*
X-295952Y-202513D01*
X-296826Y-204555D01*
X-298136Y-206305D01*
X-299665Y-207471D01*
X-301411Y-207763D01*
G01X-218861Y-252763D02*
Y-235263D01*
X-221481Y-238763D01*
G01Y-252763D02*
X-216241D01*
G01X-250570Y-190263D02*
X-245111Y-207763D01*
X-239652Y-190263D01*
G01X-223244Y-207763D02*
X-231978D01*
Y-190263D01*
X-223244D01*
G01X-226738Y-198721D02*
X-231978D01*
G01X-214478Y-207763D02*
Y-190263D01*
X-209019D01*
X-207273Y-191138D01*
X-206181Y-192305D01*
X-205744Y-194638D01*
X-206181Y-196972D01*
X-207491Y-198430D01*
X-209019Y-199305D01*
X-214478D01*
G01X-209019D02*
X-205744Y-207763D01*
G01X-192611Y-208346D02*
X-193048Y-208055D01*
Y-207471D01*
X-192611Y-207180D01*
X-192174Y-207471D01*
Y-208055D01*
X-192611Y-208346D01*
G01X-117028Y-235263D02*
Y-252763D01*
X-108294D01*
G01X-99309Y-238180D02*
X-97999Y-236430D01*
X-96471Y-235555D01*
X-94724Y-235263D01*
X-92541Y-235846D01*
X-91013Y-237305D01*
X-90576Y-239054D01*
X-90794Y-240805D01*
X-91668Y-242263D01*
X-96034Y-245180D01*
X-97999Y-247221D01*
X-99309Y-250139D01*
X-99746Y-252763D01*
X-90576D01*
G01X-76351Y-244013D02*
X-71984D01*
Y-249263D01*
X-73294Y-251013D01*
X-74823Y-252180D01*
X-77006Y-252763D01*
X-79189Y-252180D01*
X-80718Y-251013D01*
X-82028Y-249263D01*
X-82901Y-247221D01*
X-83338Y-244888D01*
Y-242846D01*
X-82901Y-241097D01*
X-82028Y-239054D01*
X-80718Y-237305D01*
X-79408Y-236138D01*
X-77661Y-235263D01*
X-76133D01*
X-74386Y-235846D01*
X-73076Y-237013D01*
G01X-65183Y-252763D02*
Y-235263D01*
X-55139Y-252763D01*
Y-235263D01*
G01X-47464Y-252763D02*
Y-235263D01*
X-43098D01*
X-41351Y-236138D01*
X-40041Y-237305D01*
X-38949Y-239054D01*
X-38076Y-241097D01*
X-37858Y-244013D01*
X-38076Y-246930D01*
X-38949Y-248972D01*
X-40041Y-250722D01*
X-41351Y-251888D01*
X-43098Y-252763D01*
X-47464D01*
G01X-125778Y-190263D02*
Y-207763D01*
X-117044D01*
G01X-99981D02*
Y-196097D01*
G01Y-198138D02*
X-100854Y-196972D01*
X-102165Y-196388D01*
X-103693Y-196097D01*
X-105221Y-196680D01*
X-106531Y-197846D01*
X-107405Y-199596D01*
X-107841Y-201930D01*
X-107405Y-204263D01*
X-106531Y-206013D01*
X-105221Y-207180D01*
X-103693Y-207763D01*
X-102165Y-207471D01*
X-100854Y-206597D01*
X-99981Y-205430D01*
G01X-90996Y-213013D02*
X-89686Y-213596D01*
X-87939Y-213013D01*
X-86848Y-211847D01*
X-85974Y-210388D01*
X-84665Y-205722D01*
X-81826Y-196097D01*
G01X-88813D02*
X-84665Y-205722D01*
G01X-72186Y-199888D02*
X-65199D01*
X-65854Y-197846D01*
X-66946Y-196680D01*
X-68474Y-196097D01*
X-70003Y-196388D01*
X-71313Y-197263D01*
X-72186Y-199305D01*
X-72623Y-201055D01*
Y-202805D01*
X-72186Y-204555D01*
X-71094Y-206305D01*
X-69784Y-207471D01*
X-68256Y-207763D01*
X-66728Y-207180D01*
X-65199Y-205430D01*
G01X-54468Y-207763D02*
Y-196097D01*
G01Y-198430D02*
X-53376Y-197263D01*
X-52284Y-196388D01*
X-50756Y-196097D01*
X-49665Y-196388D01*
X-48354Y-197263D01*
G01X-37186Y-205722D02*
X-36094Y-206888D01*
X-34566Y-207763D01*
X-33256D01*
X-31946Y-207180D01*
X-31073Y-206305D01*
X-30636Y-205139D01*
X-30854Y-203388D01*
X-31728Y-202513D01*
X-35658Y-200763D01*
X-36531Y-198721D01*
X-36094Y-197263D01*
X-35221Y-196388D01*
X-33911Y-196097D01*
X-32601Y-196388D01*
X-31291Y-197263D01*
G01X51772Y-235263D02*
Y-252763D01*
X60506D01*
G01X68836Y-235263D02*
Y-247805D01*
X69709Y-250430D01*
X71456Y-252180D01*
X73639Y-252763D01*
X75822Y-252180D01*
X77569Y-250430D01*
X78442Y-247805D01*
Y-235263D01*
G01X95942Y-236722D02*
X94632Y-235846D01*
X93104Y-235263D01*
X91357D01*
X89392Y-236138D01*
X87864Y-237596D01*
X86772Y-239347D01*
X85899Y-242263D01*
X85680Y-244888D01*
X86117Y-247513D01*
X86772Y-249263D01*
X88082Y-251013D01*
X89611Y-252180D01*
X91139Y-252763D01*
X92667D01*
X94196Y-252180D01*
X95506Y-251305D01*
X96598Y-250139D01*
G01X103836Y-252763D02*
Y-235263D01*
G01X112132D02*
X103836Y-246055D01*
G01X113442Y-252763D02*
X107547Y-241097D01*
G01X126139Y-252763D02*
Y-244888D01*
X121772Y-235263D01*
G01X130506D02*
X126139Y-244888D01*
G01X25086Y-207763D02*
Y-190263D01*
X29452D01*
X31199Y-191138D01*
X32509Y-192305D01*
X33601Y-194054D01*
X34474Y-196097D01*
X34692Y-199013D01*
X34474Y-201930D01*
X33601Y-203972D01*
X32509Y-205722D01*
X31199Y-206888D01*
X29452Y-207763D01*
X25086D01*
G01X44114Y-199888D02*
X51101D01*
X50446Y-197846D01*
X49354Y-196680D01*
X47826Y-196097D01*
X46297Y-196388D01*
X44987Y-197263D01*
X44114Y-199305D01*
X43677Y-201055D01*
Y-202805D01*
X44114Y-204555D01*
X45206Y-206305D01*
X46516Y-207471D01*
X48044Y-207763D01*
X49572Y-207180D01*
X51101Y-205430D01*
G01X61614Y-205722D02*
X62706Y-206888D01*
X64234Y-207763D01*
X65544D01*
X66854Y-207180D01*
X67727Y-206305D01*
X68164Y-205139D01*
X67946Y-203388D01*
X67072Y-202513D01*
X63142Y-200763D01*
X62269Y-198721D01*
X62706Y-197263D01*
X63579Y-196388D01*
X64889Y-196097D01*
X66199Y-196388D01*
X67509Y-197263D01*
G01X82389Y-196097D02*
Y-207763D01*
G01Y-191430D02*
X81952Y-191138D01*
Y-190555D01*
X82389Y-190263D01*
X82826Y-190555D01*
Y-191138D01*
X82389Y-191430D01*
G01X96832Y-212138D02*
X98361Y-213305D01*
X100107Y-213596D01*
X101635Y-213305D01*
X102946Y-211847D01*
X103819Y-209805D01*
Y-196097D01*
G01Y-198430D02*
X102946Y-197263D01*
X101635Y-196388D01*
X100107Y-196097D01*
X98361Y-196680D01*
X97269Y-197846D01*
X96395Y-199888D01*
X95959Y-201930D01*
X96177Y-203680D01*
X97051Y-205722D01*
X98361Y-207180D01*
X100107Y-207763D01*
X101417Y-207471D01*
X102946Y-206305D01*
X103819Y-205139D01*
G01X113677Y-207763D02*
Y-196097D01*
G01Y-199013D02*
X114551Y-197555D01*
X115861Y-196388D01*
X117607Y-196097D01*
X119135Y-196388D01*
X120446Y-197555D01*
X121101Y-199596D01*
Y-207763D01*
G01X131614Y-199888D02*
X138601D01*
X137946Y-197846D01*
X136854Y-196680D01*
X135326Y-196097D01*
X133797Y-196388D01*
X132487Y-197263D01*
X131614Y-199305D01*
X131177Y-201055D01*
Y-202805D01*
X131614Y-204555D01*
X132706Y-206305D01*
X134016Y-207471D01*
X135544Y-207763D01*
X137072Y-207180D01*
X138601Y-205430D01*
G01X149332Y-207763D02*
Y-196097D01*
G01Y-198430D02*
X150424Y-197263D01*
X151516Y-196388D01*
X153044Y-196097D01*
X154135Y-196388D01*
X155446Y-197263D01*
G01X196089Y-252763D02*
Y-235263D01*
X193469Y-238763D01*
G01Y-252763D02*
X198709D01*
G01X213589Y-235263D02*
X211842Y-235846D01*
X210532Y-237305D01*
X209659Y-239054D01*
X209004Y-241388D01*
X208786Y-244013D01*
X209004Y-246638D01*
X209659Y-248972D01*
X210532Y-250722D01*
X211842Y-252180D01*
X213589Y-252763D01*
X215335Y-252180D01*
X216646Y-250722D01*
X217519Y-248972D01*
X218174Y-246638D01*
X218392Y-244013D01*
X218174Y-241388D01*
X217519Y-239054D01*
X216646Y-237305D01*
X215335Y-235846D01*
X213589Y-235263D01*
G01X227159Y-253346D02*
X235019Y-235263D01*
G01X248589Y-252763D02*
Y-235263D01*
X245969Y-238763D01*
G01Y-252763D02*
X251209D01*
G01X261941Y-245472D02*
X263469Y-243430D01*
X264779Y-242263D01*
X266526Y-241680D01*
X268054Y-242263D01*
X269146Y-243430D01*
X270019Y-245180D01*
X270237Y-247221D01*
X270019Y-248972D01*
X269146Y-250722D01*
X267835Y-252180D01*
X266307Y-252763D01*
X264561Y-252180D01*
X263032Y-250430D01*
X262159Y-247805D01*
X261941Y-244888D01*
X262377Y-241097D01*
X263032Y-239054D01*
X264124Y-237013D01*
X265652Y-235555D01*
X267181Y-235263D01*
X268709Y-235846D01*
X269801Y-237305D01*
G01X279659Y-253346D02*
X287519Y-235263D01*
G01X296941Y-238180D02*
X298251Y-236430D01*
X299779Y-235555D01*
X301526Y-235263D01*
X303709Y-235846D01*
X305237Y-237305D01*
X305674Y-239054D01*
X305456Y-240805D01*
X304582Y-242263D01*
X300216Y-245180D01*
X298251Y-247221D01*
X296941Y-250139D01*
X296504Y-252763D01*
X305674D01*
G01X318589Y-235263D02*
X316842Y-235846D01*
X315532Y-237305D01*
X314659Y-239054D01*
X314004Y-241388D01*
X313786Y-244013D01*
X314004Y-246638D01*
X314659Y-248972D01*
X315532Y-250722D01*
X316842Y-252180D01*
X318589Y-252763D01*
X320335Y-252180D01*
X321646Y-250722D01*
X322519Y-248972D01*
X323174Y-246638D01*
X323392Y-244013D01*
X323174Y-241388D01*
X322519Y-239054D01*
X321646Y-237305D01*
X320335Y-235846D01*
X318589Y-235263D01*
G01X336089Y-252763D02*
Y-235263D01*
X333469Y-238763D01*
G01Y-252763D02*
X338709D01*
G01X349441Y-238180D02*
X350751Y-236430D01*
X352279Y-235555D01*
X354026Y-235263D01*
X356209Y-235846D01*
X357737Y-237305D01*
X358174Y-239054D01*
X357956Y-240805D01*
X357082Y-242263D01*
X352716Y-245180D01*
X350751Y-247221D01*
X349441Y-250139D01*
X349004Y-252763D01*
X358174D01*
G01X243786Y-207763D02*
Y-190263D01*
X248152D01*
X249899Y-191138D01*
X251209Y-192305D01*
X252301Y-194054D01*
X253174Y-196097D01*
X253392Y-199013D01*
X253174Y-201930D01*
X252301Y-203972D01*
X251209Y-205722D01*
X249899Y-206888D01*
X248152Y-207763D01*
X243786D01*
G01X270019D02*
Y-196097D01*
G01Y-198138D02*
X269146Y-196972D01*
X267835Y-196388D01*
X266307Y-196097D01*
X264779Y-196680D01*
X263469Y-197846D01*
X262595Y-199596D01*
X262159Y-201930D01*
X262595Y-204263D01*
X263469Y-206013D01*
X264779Y-207180D01*
X266307Y-207763D01*
X267835Y-207471D01*
X269146Y-206597D01*
X270019Y-205430D01*
G01X283589Y-190263D02*
Y-207763D01*
G01X280532Y-196097D02*
X286646D01*
G01X297814Y-199888D02*
X304801D01*
X304146Y-197846D01*
X303054Y-196680D01*
X301526Y-196097D01*
X299997Y-196388D01*
X298687Y-197263D01*
X297814Y-199305D01*
X297377Y-201055D01*
Y-202805D01*
X297814Y-204555D01*
X298906Y-206305D01*
X300216Y-207471D01*
X301744Y-207763D01*
X303272Y-207180D01*
X304801Y-205430D01*
G54D29*
G01X-771361Y-182763D02*
Y-262763D01*
G01Y-218263D02*
X373639D01*
G01X-771361Y-262763D02*
X373639D01*
G01X-775361Y-166763D02*
G02I-12000J0D01*
G01X-780511D02*
G02I-6850J0D01*
G01X-787361Y-182763D02*
Y-150763D01*
G01X-771361Y-166763D02*
X-803361D01*
G01X-771361Y-182763D02*
X373639D01*
G01X-413861D02*
Y-262763D01*
G01X-276361Y-182763D02*
Y-262763D01*
G01X-161361Y-182763D02*
Y-262763D01*
G01X6139Y-182763D02*
Y-262763D01*
G01X176139Y-182763D02*
Y-262763D01*
G01X373639Y-182763D02*
Y-262763D01*
G01X401639Y-166763D02*
G02I-12000J0D01*
G01X396489D02*
G02I-6850J0D01*
G01X389639Y-182763D02*
Y-150763D01*
G01X405639Y-166763D02*
X373639D01*
M02*
